FILE_TYPE = MACRO_DRAWING;
SET COLOR_WIRE YELLOW;
SET COLOR_PROP ORANGE;
SET COLOR_DOT WHITE;
SET COLOR_ARC YELLOW;
SET COLOR_BODY GREEN;
SET COLOR_NOTE PURPLE;
SET PROP_DISPLAY VALUE;
SET PAGE_NUMBER P337;
FORCEADD Q_RES..2
R 2
(-10225 2725);
FORCEPROP 1 LAST LOCATION R1138
J 2
(-10270 2850);
DISPLAY 0.787234 (-10270 2850);
FORCEPROP 2 LAST $SEC 1
J 0
(-10275 2950);
DISPLAY 0.680851 (-10275 2950);
PAINT MONO (-10275 2950);
DISPLAY INVISIBLE (-10275 2950);
FORCEPROP 2 LAST CDS_SEC 1
J 0
(-10275 2950);
DISPLAY 1.021277 (-10275 2950);
DISPLAY INVISIBLE (-10275 2950);
FORCEPROP 1 LASTPIN (-10225 2825) $PN 1
J 2
(-10230 2787);
DISPLAY 0.787234 (-10230 2787);
FORCEPROP 1 LASTPIN (-10225 2625) $PN 2
J 2
(-10230 2635);
DISPLAY 0.787234 (-10230 2635);
FORCEPROP 1 LAST WATTAGE 1/16W
J 2
(-10265 2700);
DISPLAY 0.510638 (-10265 2700);
FORCEPROP 1 LAST TOLERANCE 1%
J 2
(-10270 2750);
DISPLAY 0.510638 (-10270 2750);
FORCEPROP 1 LAST VALUE 10K
J 2
(-10270 2800);
DISPLAY 0.510638 (-10270 2800);
FORCEPROP 1 LAST MATERIAL CHIP
J 2
(-10265 2650);
DISPLAY 0.510638 (-10265 2650);
FORCEPROP 1 LAST PACK_TYPE 0402LF
J 2
(-10265 2550);
DISPLAY 0.510638 (-10265 2550);
FORCEPROP 2 LAST CDS_LIB pure_quanta
J 2
(-10225 2725);
PAINT MONO (-10225 2725);
DISPLAY INVISIBLE (-10225 2725);
FORCEPROP 1 LAST PATH I1
J 2
(-10275 2900);
DISPLAY 0.978723 (-10275 2900);
PAINT WHITE (-10275 2900);
DISPLAY INVISIBLE (-10275 2900);
FORCEPROP 1 LAST PART_NUMBER CS31002FB08
J 2
(-10265 2600);
DISPLAY 0.510638 (-10265 2600);
DISPLAY INVISIBLE (-10265 2600);
FORCEADD OFFPAGE..1
(-10200 4300);
FORCEPROP 2 LAST $XR0 131 
J 0
(-10452 4300);
DISPLAY 0.638298 (-10452 4300);
PAINT MONO (-10452 4300);
FORCEPROP 2 LAST CDS_LIB standard
J 0
(-10200 4300);
PAINT MONO (-10200 4300);
DISPLAY INVISIBLE (-10200 4300);
FORCEPROP 1 LAST OFFPAGE TRUE
J 0
(-9875 4175);
DISPLAY 0.872340 (-9875 4175);
PAINT GREEN (-9875 4175);
DISPLAY INVISIBLE (-9875 4175);
FORCEPROP 1 LAST COMMENT_BODY TRUE
J 0
(-10075 4200);
DISPLAY 0.872340 (-10075 4200);
PAINT GREEN (-10075 4200);
DISPLAY INVISIBLE (-10075 4200);
FORCEPROP 2 LAST PATH I10
J 0
(-10450 4350);
DISPLAY 0.680851 (-10450 4350);
DISPLAY INVISIBLE (-10450 4350);
FORCEADD Q_RES..2
R 2
(-9675 4625);
FORCEPROP 1 LAST LOCATION R1824
J 2
(-9720 4750);
DISPLAY 0.787234 (-9720 4750);
FORCEPROP 2 LAST $SEC 1
J 0
(-9725 4850);
DISPLAY 0.680851 (-9725 4850);
PAINT MONO (-9725 4850);
DISPLAY INVISIBLE (-9725 4850);
FORCEPROP 2 LAST CDS_SEC 1
J 0
(-9725 4850);
DISPLAY 1.021277 (-9725 4850);
DISPLAY INVISIBLE (-9725 4850);
FORCEPROP 1 LASTPIN (-9675 4725) $PN 1
J 2
(-9680 4687);
DISPLAY 0.787234 (-9680 4687);
FORCEPROP 1 LASTPIN (-9675 4525) $PN 2
J 2
(-9680 4535);
DISPLAY 0.787234 (-9680 4535);
FORCEPROP 1 LAST MATERIAL CHIP
J 2
(-9715 4550);
DISPLAY 0.638298 (-9715 4550);
FORCEPROP 1 LAST WATTAGE 1/16W
J 2
(-9715 4600);
DISPLAY 0.638298 (-9715 4600);
FORCEPROP 1 LAST TOLERANCE 1%
J 2
(-9720 4650);
DISPLAY 0.638298 (-9720 4650);
FORCEPROP 1 LAST PACK_TYPE 0402LF
J 2
(-9715 4450);
DISPLAY 0.638298 (-9715 4450);
FORCEPROP 1 LAST VALUE 10K
J 2
(-9720 4700);
DISPLAY 0.638298 (-9720 4700);
FORCEPROP 2 LAST CDS_LIB pure_quanta
J 2
(-9675 4625);
PAINT MONO (-9675 4625);
DISPLAY INVISIBLE (-9675 4625);
FORCEPROP 1 LAST PATH I11
J 2
(-9725 4800);
DISPLAY 0.978723 (-9725 4800);
PAINT WHITE (-9725 4800);
DISPLAY INVISIBLE (-9725 4800);
FORCEPROP 1 LAST PART_NUMBER CS31002FB08
J 2
(-9715 4500);
DISPLAY 0.638298 (-9715 4500);
DISPLAY INVISIBLE (-9715 4500);
FORCEADD Q_RES..2
(-9400 4625);
FORCEPROP 1 LAST LOCATION R45
J 0
(-9355 4750);
DISPLAY 0.808511 (-9355 4750);
FORCEPROP 2 LAST $SEC 1
J 2
(-9350 4850);
DISPLAY 0.680851 (-9350 4850);
PAINT MONO (-9350 4850);
DISPLAY INVISIBLE (-9350 4850);
FORCEPROP 2 LAST CDS_SEC 1
J 2
(-9350 4850);
DISPLAY 1.021277 (-9350 4850);
DISPLAY INVISIBLE (-9350 4850);
FORCEPROP 1 LASTPIN (-9400 4725) $PN 1
J 0
(-9395 4687);
DISPLAY 0.787234 (-9395 4687);
FORCEPROP 1 LASTPIN (-9400 4525) $PN 2
J 0
(-9395 4535);
DISPLAY 0.787234 (-9395 4535);
FORCEPROP 1 LAST TOLERANCE 1%
J 0
(-9355 4650);
DISPLAY 0.638298 (-9355 4650);
FORCEPROP 1 LAST VALUE 10K
J 0
(-9355 4700);
DISPLAY 0.638298 (-9355 4700);
FORCEPROP 1 LAST MATERIAL CHIP
J 0
(-9360 4550);
DISPLAY 0.638298 (-9360 4550);
FORCEPROP 1 LAST WATTAGE 1/16W
J 0
(-9360 4600);
DISPLAY 0.638298 (-9360 4600);
FORCEPROP 1 LAST PACK_TYPE 0402LF
J 0
(-9360 4450);
DISPLAY 0.638298 (-9360 4450);
FORCEPROP 2 LAST CDS_LIB pure_quanta
J 0
(-9400 4625);
PAINT MONO (-9400 4625);
DISPLAY INVISIBLE (-9400 4625);
FORCEPROP 1 LAST PATH I12
J 0
(-9350 4800);
DISPLAY 0.978723 (-9350 4800);
PAINT WHITE (-9350 4800);
DISPLAY INVISIBLE (-9350 4800);
FORCEPROP 1 LAST PART_NUMBER CS31002FB08
J 0
(-9360 4500);
DISPLAY 0.638298 (-9360 4500);
DISPLAY INVISIBLE (-9360 4500);
FORCEADD UNIVERSAL_POWER..1
(-9400 4975);
FORCEPROP 3 LASTPIN (-9400 4925) SIG_NAME P3V3_OCP_SFF\g
J 0
(-9390 4935);
DISPLAY 0.659574 (-9390 4935);
PAINT MONO (-9390 4935);
DISPLAY INVISIBLE (-9390 4935);
FORCEPROP 1 LAST HDL_POWER P3V3_OCP_SFF
J 1
(-9400 5025);
DISPLAY 0.872340 (-9400 5025);
PAINT GREEN (-9400 5025);
FORCEPROP 2 LAST CDS_LIB pure_quanta_power
J 0
(-9400 4975);
PAINT MONO (-9400 4975);
DISPLAY INVISIBLE (-9400 4975);
FORCEPROP 1 LAST PATH I13
J 0
(-9350 5000);
DISPLAY 0.872340 (-9350 5000);
PAINT AQUA (-9350 5000);
DISPLAY INVISIBLE (-9350 5000);
FORCEADD OFFPAGE..1
(-8700 5825);
FORCEPROP 2 LAST $XR2 139 
J 0
(-9161 5825);
DISPLAY 0.638298 (-9161 5825);
PAINT MONO (-9161 5825);
FORCEPROP 2 LAST $XR1 83 
J 0
(-9041 5825);
DISPLAY 0.638298 (-9041 5825);
PAINT MONO (-9041 5825);
FORCEPROP 2 LAST $XR0 80 
J 0
(-8951 5825);
DISPLAY 0.638298 (-8951 5825);
PAINT MONO (-8951 5825);
FORCEPROP 2 LAST CDS_LIB standard
J 0
(-8700 5825);
PAINT MONO (-8700 5825);
DISPLAY INVISIBLE (-8700 5825);
FORCEPROP 1 LAST OFFPAGE TRUE
J 0
(-8375 5700);
DISPLAY 0.872340 (-8375 5700);
PAINT GREEN (-8375 5700);
DISPLAY INVISIBLE (-8375 5700);
FORCEPROP 1 LAST COMMENT_BODY TRUE
J 0
(-8575 5725);
DISPLAY 0.872340 (-8575 5725);
PAINT GREEN (-8575 5725);
DISPLAY INVISIBLE (-8575 5725);
FORCEPROP 2 LAST PATH I14
J 0
(-8950 5875);
DISPLAY 0.680851 (-8950 5875);
DISPLAY INVISIBLE (-8950 5875);
FORCEADD UNIVERSAL_GND..1
(-6550 2150);
FORCEPROP 3 LASTPIN (-6550 2200) SIG_NAME GND\g
J 0
(-6540 2210);
DISPLAY 0.659574 (-6540 2210);
PAINT MONO (-6540 2210);
DISPLAY INVISIBLE (-6540 2210);
FORCEPROP 2 LAST ROOM IO_SLOT
J 1
(-6775 2225);
DISPLAY 0.744681 (-6775 2225);
FORCEPROP 2 LAST CDS_LIB pure_quanta_power
J 0
(-6550 2150);
PAINT MONO (-6550 2150);
DISPLAY INVISIBLE (-6550 2150);
FORCEPROP 1 LAST HDL_POWER GND
J 1
(-6525 2075);
DISPLAY 0.872340 (-6525 2075);
PAINT GREEN (-6525 2075);
DISPLAY INVISIBLE (-6525 2075);
FORCEPROP 1 LAST PATH I15
J 0
(-6475 2150);
DISPLAY 0.872340 (-6475 2150);
PAINT AQUA (-6475 2150);
DISPLAY INVISIBLE (-6475 2150);
FORCEADD PI6CV304LE..1
(-6975 2450);
FORCEPROP 1 LAST LOCATION U90
J 0
(-7125 2751);
DISPLAY 0.723404 (-7125 2751);
PAINT GREEN (-7125 2751);
FORCEPROP 2 LAST $SEC 1
J 0
(-7125 2900);
DISPLAY 0.680851 (-7125 2900);
PAINT MONO (-7125 2900);
DISPLAY INVISIBLE (-7125 2900);
FORCEPROP 2 LAST CDS_SEC 1
J 0
(-7125 2900);
DISPLAY 1.021277 (-7125 2900);
DISPLAY INVISIBLE (-7125 2900);
FORCEPROP 2 LASTPIN (-7275 2525) $PN 1
J 2
(-7285 2535);
DISPLAY 0.808511 (-7285 2535);
FORCEPROP 2 LASTPIN (-6675 2275) $PN 4
J 0
(-6665 2285);
DISPLAY 0.808511 (-6665 2285);
FORCEPROP 2 LASTPIN (-7275 2375) $PN 2
J 2
(-7285 2385);
DISPLAY 0.808511 (-7285 2385);
FORCEPROP 2 LASTPIN (-6675 2625) $PN 6
J 0
(-6665 2635);
DISPLAY 0.808511 (-6665 2635);
FORCEPROP 2 LASTPIN (-6675 2525) $PN 3
J 0
(-6665 2535);
DISPLAY 0.808511 (-6665 2535);
FORCEPROP 2 LASTPIN (-6675 2475) $PN 5
J 0
(-6665 2485);
DISPLAY 0.808511 (-6665 2485);
FORCEPROP 2 LASTPIN (-6675 2425) $PN 7
J 0
(-6665 2435);
DISPLAY 0.808511 (-6665 2435);
FORCEPROP 2 LASTPIN (-6675 2375) $PN 8
J 0
(-6665 2385);
DISPLAY 0.808511 (-6665 2385);
FORCEPROP 1 LAST MATERIAL IC
J 0
(-7125 2682);
DISPLAY 0.723404 (-7125 2682);
PAINT GREEN (-7125 2682);
FORCEPROP 2 LAST VALUE PI6CV304LE
J 0
(-7125 2800);
DISPLAY 1.021277 (-7125 2800);
FORCEPROP 2 LAST PART_TYPE SMLF
J 0
(-7125 2850);
DISPLAY 1.021277 (-7125 2850);
FORCEPROP 1 LAST CDS_LMAN_SYM_OUTLINE -150,225,150,-225
J 0
(-6975 2450);
DISPLAY 0.468085 (-6975 2450);
PAINT GREEN (-6975 2450);
DISPLAY INVISIBLE (-6975 2450);
FORCEPROP 2 LAST CDS_LIB pure_quanta
J 0
(-6975 2450);
PAINT MONO (-6975 2450);
DISPLAY INVISIBLE (-6975 2450);
FORCEPROP 1 LAST PATH I16
J 0
(-6825 2185);
DISPLAY 0.723404 (-6825 2185);
PAINT GREEN (-6825 2185);
DISPLAY INVISIBLE (-6825 2185);
FORCEPROP 1 LAST PART_NUMBER AL000304K01
J 0
(-7125 2717);
DISPLAY 0.723404 (-7125 2717);
PAINT GREEN (-7125 2717);
DISPLAY INVISIBLE (-7125 2717);
FORCEADD UNIVERSAL_POWER..1
(-6475 3175);
FORCEPROP 3 LASTPIN (-6475 3125) SIG_NAME P3V3_AUX\g
J 0
(-6465 3135);
DISPLAY 0.659574 (-6465 3135);
PAINT MONO (-6465 3135);
DISPLAY INVISIBLE (-6465 3135);
FORCEPROP 1 LAST HDL_POWER P3V3_AUX
J 1
(-6475 3225);
DISPLAY 0.872340 (-6475 3225);
PAINT GREEN (-6475 3225);
FORCEPROP 2 LAST CDS_LIB pure_quanta_power
J 0
(-6475 3175);
PAINT MONO (-6475 3175);
DISPLAY INVISIBLE (-6475 3175);
FORCEPROP 1 LAST PATH I17
J 0
(-6425 3200);
DISPLAY 0.872340 (-6425 3200);
PAINT AQUA (-6425 3200);
DISPLAY INVISIBLE (-6425 3200);
FORCEADD UNIVERSAL_GND..1
(-6250 2625);
FORCEPROP 3 LASTPIN (-6250 2675) SIG_NAME GND\g
J 0
(-6240 2685);
DISPLAY 0.659574 (-6240 2685);
PAINT MONO (-6240 2685);
DISPLAY INVISIBLE (-6240 2685);
FORCEPROP 2 LAST CDS_LIB pure_quanta_power
J 0
(-6250 2625);
PAINT MONO (-6250 2625);
DISPLAY INVISIBLE (-6250 2625);
FORCEPROP 1 LAST HDL_POWER GND
J 1
(-6225 2550);
DISPLAY 0.872340 (-6225 2550);
PAINT GREEN (-6225 2550);
DISPLAY INVISIBLE (-6225 2550);
FORCEPROP 1 LAST PATH I18
J 0
(-6175 2625);
DISPLAY 0.872340 (-6175 2625);
PAINT AQUA (-6175 2625);
DISPLAY INVISIBLE (-6175 2625);
FORCEADD Q_CAP..1
(-6250 2850);
FORCEPROP 1 LAST LOCATION C1275
J 0
(-6200 2950);
DISPLAY 0.978723 (-6200 2950);
FORCEPROP 2 LAST $SEC 1
J 0
(-6200 3050);
DISPLAY 0.680851 (-6200 3050);
PAINT MONO (-6200 3050);
DISPLAY INVISIBLE (-6200 3050);
FORCEPROP 2 LAST CDS_SEC 1
J 0
(-6200 3050);
DISPLAY 1.021277 (-6200 3050);
DISPLAY INVISIBLE (-6200 3050);
FORCEPROP 1 LASTPIN (-6250 2950) $PN 1
J 0
(-6240 2930);
DISPLAY 0.787234 (-6240 2930);
FORCEPROP 1 LASTPIN (-6250 2750) $PN 2
J 0
(-6240 2730);
DISPLAY 0.787234 (-6240 2730);
FORCEPROP 1 LAST VOLTAGE 25V
J 0
(-6200 2850);
DISPLAY 0.510638 (-6200 2850);
FORCEPROP 1 LAST MATERIAL X7R
J 0
(-6200 2750);
DISPLAY 0.510638 (-6200 2750);
FORCEPROP 1 LAST VALUE 0.1UF
J 0
(-6200 2900);
DISPLAY 0.510638 (-6200 2900);
FORCEPROP 1 LAST TOLERANCE 10%
J 0
(-6200 2800);
DISPLAY 0.510638 (-6200 2800);
FORCEPROP 1 LAST PACK_TYPE 0402
J 0
(-6200 2650);
DISPLAY 0.510638 (-6200 2650);
FORCEPROP 2 LAST CDS_LIB pure_quanta
J 0
(-6250 2850);
PAINT MONO (-6250 2850);
DISPLAY INVISIBLE (-6250 2850);
FORCEPROP 1 LAST PATH I19
J 0
(-6200 3000);
DISPLAY 0.978723 (-6200 3000);
PAINT WHITE (-6200 3000);
DISPLAY INVISIBLE (-6200 3000);
FORCEPROP 1 LAST PART_NUMBER CH4104K1B00
J 0
(-6200 2700);
DISPLAY 0.510638 (-6200 2700);
DISPLAY INVISIBLE (-6200 2700);
FORCEADD UNIVERSAL_GND..1
(-9875 2525);
FORCEPROP 3 LASTPIN (-9875 2575) SIG_NAME GND\g
J 0
(-9865 2585);
DISPLAY 0.659574 (-9865 2585);
PAINT MONO (-9865 2585);
DISPLAY INVISIBLE (-9865 2585);
FORCEPROP 2 LAST ROOM IO_SLOT
J 1
(-10100 2600);
DISPLAY 0.744681 (-10100 2600);
FORCEPROP 2 LAST CDS_LIB pure_quanta_power
J 0
(-9875 2525);
PAINT MONO (-9875 2525);
DISPLAY INVISIBLE (-9875 2525);
FORCEPROP 1 LAST HDL_POWER GND
J 1
(-9850 2450);
DISPLAY 0.872340 (-9850 2450);
PAINT GREEN (-9850 2450);
DISPLAY INVISIBLE (-9850 2450);
FORCEPROP 1 LAST PATH I2
J 0
(-9800 2525);
DISPLAY 0.872340 (-9800 2525);
PAINT AQUA (-9800 2525);
DISPLAY INVISIBLE (-9800 2525);
FORCEADD Q_RES..1
(-5550 2425);
FORCEPROP 1 LAST LOCATION R3181
J 0
(-5800 2425);
DISPLAY 0.638298 (-5800 2425);
FORCEPROP 2 LAST $SEC 1
J 0
(-5600 2625);
DISPLAY 0.680851 (-5600 2625);
PAINT MONO (-5600 2625);
DISPLAY INVISIBLE (-5600 2625);
FORCEPROP 2 LAST CDS_SEC 1
J 0
(-5600 2625);
DISPLAY 1.021277 (-5600 2625);
DISPLAY INVISIBLE (-5600 2625);
FORCEPROP 1 LASTPIN (-5650 2425) $PN 1
J 0
(-5638 2437);
DISPLAY 0.787234 (-5638 2437);
FORCEPROP 1 LASTPIN (-5450 2425) $PN 2
J 0
(-5488 2437);
DISPLAY 0.787234 (-5488 2437);
FORCEPROP 1 LAST MATERIAL CHIP
J 0
(-5225 2425);
DISPLAY 0.510638 (-5225 2425);
FORCEPROP 1 LAST VALUE 27.4
J 2
(-5325 2425);
DISPLAY 0.510638 (-5325 2425);
FORCEPROP 1 LAST TOLERANCE 1%
J 0
(-5300 2425);
DISPLAY 0.510638 (-5300 2425);
FORCEPROP 1 LAST WATTAGE 1/16W
J 2
(-5400 2525);
DISPLAY 0.404255 (-5400 2525);
DISPLAY INVISIBLE (-5400 2525);
FORCEPROP 2 LAST CDS_LIB pure_quanta
J 0
(-5550 2425);
PAINT MONO (-5550 2425);
DISPLAY INVISIBLE (-5550 2425);
FORCEPROP 1 LAST PACK_TYPE 0402LF
J 0
(-5225 2425);
DISPLAY 0.510638 (-5225 2425);
DISPLAY INVISIBLE (-5225 2425);
FORCEPROP 1 LAST PATH I20
J 0
(-5600 2575);
DISPLAY 0.978723 (-5600 2575);
PAINT WHITE (-5600 2575);
DISPLAY INVISIBLE (-5600 2575);
FORCEPROP 1 LAST PART_NUMBER CS02742FB03
J 0
(-5625 2500);
DISPLAY 0.404255 (-5625 2500);
DISPLAY INVISIBLE (-5625 2500);
FORCEADD Q_RES..1
(-5550 2475);
FORCEPROP 1 LAST LOCATION R1141
J 0
(-5800 2475);
DISPLAY 0.638298 (-5800 2475);
FORCEPROP 2 LAST $SEC 1
J 0
(-5600 2675);
DISPLAY 0.680851 (-5600 2675);
PAINT MONO (-5600 2675);
DISPLAY INVISIBLE (-5600 2675);
FORCEPROP 2 LAST CDS_SEC 1
J 0
(-5600 2675);
DISPLAY 1.021277 (-5600 2675);
DISPLAY INVISIBLE (-5600 2675);
FORCEPROP 1 LASTPIN (-5650 2475) $PN 1
J 0
(-5638 2487);
DISPLAY 0.787234 (-5638 2487);
FORCEPROP 1 LASTPIN (-5450 2475) $PN 2
J 0
(-5488 2487);
DISPLAY 0.787234 (-5488 2487);
FORCEPROP 1 LAST VALUE 27.4
J 2
(-5325 2475);
DISPLAY 0.510638 (-5325 2475);
FORCEPROP 1 LAST MATERIAL CHIP
J 0
(-5225 2475);
DISPLAY 0.510638 (-5225 2475);
FORCEPROP 1 LAST TOLERANCE 1%
J 0
(-5300 2475);
DISPLAY 0.510638 (-5300 2475);
FORCEPROP 1 LAST PACK_TYPE 0402LF
J 0
(-5225 2475);
DISPLAY 0.510638 (-5225 2475);
DISPLAY INVISIBLE (-5225 2475);
FORCEPROP 2 LAST CDS_LIB pure_quanta
J 0
(-5550 2475);
PAINT MONO (-5550 2475);
DISPLAY INVISIBLE (-5550 2475);
FORCEPROP 1 LAST WATTAGE 1/16W
J 2
(-5400 2575);
DISPLAY 0.404255 (-5400 2575);
DISPLAY INVISIBLE (-5400 2575);
FORCEPROP 1 LAST PATH I21
J 0
(-5600 2625);
DISPLAY 0.978723 (-5600 2625);
PAINT WHITE (-5600 2625);
DISPLAY INVISIBLE (-5600 2625);
FORCEPROP 1 LAST PART_NUMBER CS02742FB03
J 0
(-5625 2550);
DISPLAY 0.404255 (-5625 2550);
DISPLAY INVISIBLE (-5625 2550);
FORCEADD Q_RES..1
(-5550 2525);
FORCEPROP 1 LAST LOCATION R1140
J 0
(-5800 2525);
DISPLAY 0.638298 (-5800 2525);
FORCEPROP 2 LAST $SEC 1
J 0
(-5600 2725);
DISPLAY 0.680851 (-5600 2725);
PAINT MONO (-5600 2725);
DISPLAY INVISIBLE (-5600 2725);
FORCEPROP 2 LAST CDS_SEC 1
J 0
(-5600 2725);
DISPLAY 1.021277 (-5600 2725);
DISPLAY INVISIBLE (-5600 2725);
FORCEPROP 1 LASTPIN (-5650 2525) $PN 1
J 0
(-5638 2537);
DISPLAY 0.787234 (-5638 2537);
FORCEPROP 1 LASTPIN (-5450 2525) $PN 2
J 0
(-5488 2537);
DISPLAY 0.787234 (-5488 2537);
FORCEPROP 1 LAST TOLERANCE 1%
J 0
(-5300 2525);
DISPLAY 0.510638 (-5300 2525);
FORCEPROP 1 LAST VALUE 27.4
J 2
(-5325 2525);
DISPLAY 0.510638 (-5325 2525);
FORCEPROP 1 LAST WATTAGE 1/16W
J 2
(-5375 2625);
DISPLAY 0.404255 (-5375 2625);
FORCEPROP 1 LAST MATERIAL CHIP
J 0
(-5225 2525);
DISPLAY 0.510638 (-5225 2525);
FORCEPROP 1 LAST PACK_TYPE 0402LF
J 0
(-5625 2625);
DISPLAY 0.404255 (-5625 2625);
FORCEPROP 2 LAST CDS_LIB pure_quanta
J 0
(-5550 2525);
PAINT MONO (-5550 2525);
DISPLAY INVISIBLE (-5550 2525);
FORCEPROP 1 LAST PATH I22
J 0
(-5600 2675);
DISPLAY 0.978723 (-5600 2675);
PAINT WHITE (-5600 2675);
DISPLAY INVISIBLE (-5600 2675);
FORCEPROP 1 LAST PART_NUMBER CS02742FB03
J 0
(-5625 2600);
DISPLAY 0.404255 (-5625 2600);
DISPLAY INVISIBLE (-5625 2600);
FORCEADD OFFPAGE..2
R 2
(-5700 3275);
FORCEPROP 2 LAST $XR0 131 
J 0
(-5985 3275);
DISPLAY 0.638298 (-5985 3275);
PAINT MONO (-5985 3275);
FORCEPROP 2 LAST CDS_LIB standard
J 2
(-5700 3275);
DISPLAY INVISIBLE (-5700 3275);
FORCEPROP 1 LAST OFFPAGE TRUE
J 2
(-6025 3150);
DISPLAY 0.872340 (-6025 3150);
PAINT GREEN (-6025 3150);
DISPLAY INVISIBLE (-6025 3150);
FORCEPROP 1 LAST COMMENT_BODY TRUE
J 2
(-5655 3180);
DISPLAY 0.872340 (-5655 3180);
PAINT GREEN (-5655 3180);
DISPLAY INVISIBLE (-5655 3180);
FORCEPROP 2 LAST PATH I23
J 0
(-5950 3325);
DISPLAY 0.680851 (-5950 3325);
DISPLAY INVISIBLE (-5950 3325);
FORCEADD UNIVERSAL_GND..1
(-5425 3925);
FORCEPROP 3 LASTPIN (-5425 3975) SIG_NAME GND\g
J 0
(-5415 3985);
DISPLAY 0.659574 (-5415 3985);
PAINT MONO (-5415 3985);
DISPLAY INVISIBLE (-5415 3985);
FORCEPROP 2 LAST CDS_LIB pure_quanta_power
J 0
(-5425 3925);
DISPLAY INVISIBLE (-5425 3925);
FORCEPROP 1 LAST HDL_POWER GND
J 1
(-5400 3850);
DISPLAY 0.872340 (-5400 3850);
PAINT GREEN (-5400 3850);
DISPLAY INVISIBLE (-5400 3850);
FORCEPROP 1 LAST PATH I24
J 0
(-5350 3925);
DISPLAY 0.872340 (-5350 3925);
PAINT AQUA (-5350 3925);
DISPLAY INVISIBLE (-5350 3925);
FORCEADD 74LVC1G07GV..1
(-4950 4250);
FORCEPROP 1 LAST LOCATION U157
J 0
(-5075 4575);
DISPLAY 0.723404 (-5075 4575);
PAINT GREEN (-5075 4575);
FORCEPROP 0 LAST $SEC 1
J 0
(-5075 4775);
DISPLAY 0.680851 (-5075 4775);
PAINT MONO (-5075 4775);
DISPLAY INVISIBLE (-5075 4775);
FORCEPROP 0 LAST CDS_SEC 1
J 0
(-5075 4775);
DISPLAY 1.021277 (-5075 4775);
DISPLAY INVISIBLE (-5075 4775);
FORCEPROP 0 LASTPIN (-5225 4250) $PN 2
J 2
(-5235 4260);
DISPLAY 0.680851 (-5235 4260);
PAINT MONO (-5235 4260);
FORCEPROP 0 LASTPIN (-5225 4150) $PN 3
J 2
(-5235 4160);
DISPLAY 0.680851 (-5235 4160);
PAINT MONO (-5235 4160);
FORCEPROP 0 LASTPIN (-5225 4350) $PN 1
J 2
(-5235 4360);
DISPLAY 0.680851 (-5235 4360);
PAINT MONO (-5235 4360);
FORCEPROP 0 LASTPIN (-4675 4350) $PN 5
J 0
(-4665 4360);
DISPLAY 0.680851 (-4665 4360);
PAINT MONO (-4665 4360);
FORCEPROP 0 LASTPIN (-4675 4150) $PN 4
J 0
(-4665 4160);
DISPLAY 0.680851 (-4665 4160);
PAINT MONO (-4665 4160);
FORCEPROP 2 LAST VALUE 74LVC1G07GV
J 0
(-5075 4675);
DISPLAY 0.638298 (-5075 4675);
FORCEPROP 2 LAST PART_TYPE SMLF
J 0
(-5075 4725);
DISPLAY 0.638298 (-5075 4725);
FORCEPROP 1 LAST MATERIAL IC
J 0
(-5069 4432);
DISPLAY 0.723404 (-5069 4432);
PAINT GREEN (-5069 4432);
FORCEPROP 2 LAST CDS_LIB pure_quanta
J 0
(-4950 4250);
DISPLAY INVISIBLE (-4950 4250);
FORCEPROP 1 LAST CDS_LMAN_SYM_OUTLINE -125,150,125,-150
J 0
(-4950 4250);
DISPLAY 0.468085 (-4950 4250);
PAINT GREEN (-4950 4250);
DISPLAY INVISIBLE (-4950 4250);
FORCEPROP 1 LAST NEEDS_NO_SIZE TRUE
J 0
(-4950 4250);
DISPLAY 0.723404 (-4950 4250);
PAINT GREEN (-4950 4250);
DISPLAY INVISIBLE (-4950 4250);
FORCEPROP 1 LAST PATH I25
J 0
(-4950 4250);
DISPLAY 0.723404 (-4950 4250);
PAINT GREEN (-4950 4250);
DISPLAY INVISIBLE (-4950 4250);
FORCEPROP 1 LAST PART_NUMBER AL1G0007001
J 0
(-5075 4500);
DISPLAY 0.723404 (-5075 4500);
PAINT GREEN (-5075 4500);
DISPLAY INVISIBLE (-5075 4500);
FORCEADD OFFPAGE..2
(-4350 2425);
FORCEPROP 2 LAST $XR0 139 
J 0
(-4161 2425);
DISPLAY 0.638298 (-4161 2425);
PAINT MONO (-4161 2425);
FORCEPROP 2 LAST CDS_LIB standard
J 0
(-4350 2425);
PAINT MONO (-4350 2425);
DISPLAY INVISIBLE (-4350 2425);
FORCEPROP 1 LAST OFFPAGE TRUE
J 0
(-4025 2300);
DISPLAY 0.872340 (-4025 2300);
PAINT GREEN (-4025 2300);
DISPLAY INVISIBLE (-4025 2300);
FORCEPROP 1 LAST COMMENT_BODY TRUE
J 0
(-4395 2330);
DISPLAY 0.872340 (-4395 2330);
PAINT GREEN (-4395 2330);
DISPLAY INVISIBLE (-4395 2330);
FORCEPROP 2 LAST PATH I26
J 0
(-4150 2475);
DISPLAY 0.680851 (-4150 2475);
DISPLAY INVISIBLE (-4150 2475);
FORCEADD OFFPAGE..2
(-4350 2475);
FORCEPROP 2 LAST $XR0 133 
J 0
(-4161 2475);
DISPLAY 0.638298 (-4161 2475);
PAINT MONO (-4161 2475);
FORCEPROP 2 LAST CDS_LIB standard
J 0
(-4350 2475);
PAINT MONO (-4350 2475);
DISPLAY INVISIBLE (-4350 2475);
FORCEPROP 1 LAST OFFPAGE TRUE
J 0
(-4025 2350);
DISPLAY 0.872340 (-4025 2350);
PAINT GREEN (-4025 2350);
DISPLAY INVISIBLE (-4025 2350);
FORCEPROP 1 LAST COMMENT_BODY TRUE
J 0
(-4395 2380);
DISPLAY 0.872340 (-4395 2380);
PAINT GREEN (-4395 2380);
DISPLAY INVISIBLE (-4395 2380);
FORCEPROP 2 LAST PATH I27
J 0
(-4150 2525);
DISPLAY 0.680851 (-4150 2525);
DISPLAY INVISIBLE (-4150 2525);
FORCEADD OFFPAGE..2
(-4350 2525);
FORCEPROP 2 LAST $XR0 150 
J 0
(-4161 2525);
DISPLAY 0.638298 (-4161 2525);
PAINT MONO (-4161 2525);
FORCEPROP 2 LAST CDS_LIB standard
J 0
(-4350 2525);
PAINT MONO (-4350 2525);
DISPLAY INVISIBLE (-4350 2525);
FORCEPROP 1 LAST OFFPAGE TRUE
J 0
(-4025 2400);
DISPLAY 0.872340 (-4025 2400);
PAINT GREEN (-4025 2400);
DISPLAY INVISIBLE (-4025 2400);
FORCEPROP 1 LAST COMMENT_BODY TRUE
J 0
(-4395 2430);
DISPLAY 0.872340 (-4395 2430);
PAINT GREEN (-4395 2430);
DISPLAY INVISIBLE (-4395 2430);
FORCEPROP 2 LAST PATH I28
J 0
(-4150 2575);
DISPLAY 0.680851 (-4150 2575);
DISPLAY INVISIBLE (-4150 2575);
FORCEADD Q_RES..1
(-4625 3275);
FORCEPROP 1 LAST LOCATION R4601
J 0
(-4825 3275);
DISPLAY 0.638298 (-4825 3275);
FORCEPROP 0 LAST $SEC 1
J 0
(-4825 3325);
DISPLAY 0.680851 (-4825 3325);
PAINT MONO (-4825 3325);
DISPLAY INVISIBLE (-4825 3325);
FORCEPROP 0 LAST CDS_SEC 1
J 0
(-4825 3325);
DISPLAY 1.021277 (-4825 3325);
DISPLAY INVISIBLE (-4825 3325);
FORCEPROP 1 LASTPIN (-4725 3275) $PN 1
J 0
(-4713 3287);
DISPLAY 0.787234 (-4713 3287);
PAINT MONO (-4713 3287);
FORCEPROP 1 LASTPIN (-4525 3275) $PN 2
J 0
(-4563 3287);
DISPLAY 0.787234 (-4563 3287);
PAINT MONO (-4563 3287);
FORCEPROP 1 LAST VALUE 0
J 2
(-4500 3275);
DISPLAY 0.510638 (-4500 3275);
FORCEPROP 1 LAST MATERIAL CHIP
J 0
(-4400 3275);
DISPLAY 0.510638 (-4400 3275);
FORCEPROP 2 LAST CDS_LIB pure_quanta
J 0
(-4625 3275);
DISPLAY INVISIBLE (-4625 3275);
FORCEPROP 1 LAST PACK_TYPE 0402LF
J 0
(-4725 3375);
DISPLAY 0.510638 (-4725 3375);
DISPLAY INVISIBLE (-4725 3375);
FORCEPROP 1 LAST TOLERANCE 5%
J 0
(-4475 3275);
DISPLAY 0.510638 (-4475 3275);
DISPLAY INVISIBLE (-4475 3275);
FORCEPROP 1 LAST WATTAGE 1/16W
J 2
(-4375 3375);
DISPLAY 0.510638 (-4375 3375);
DISPLAY INVISIBLE (-4375 3375);
FORCEPROP 1 LAST PATH I29
J 0
(-4675 3425);
DISPLAY 0.978723 (-4675 3425);
PAINT WHITE (-4675 3425);
DISPLAY INVISIBLE (-4675 3425);
FORCEPROP 1 LAST PART_NUMBER CS00002JB13
J 0
(-4725 3325);
DISPLAY 0.510638 (-4725 3325);
DISPLAY INVISIBLE (-4725 3325);
FORCEADD Q_CAP..1
R 2
(-9875 2750);
FORCEPROP 1 LAST LOCATION C1274
J 2
(-9925 2850);
DISPLAY 0.787234 (-9925 2850);
FORCEPROP 2 LAST $SEC 1
J 0
(-9925 2950);
DISPLAY 0.680851 (-9925 2950);
PAINT MONO (-9925 2950);
DISPLAY INVISIBLE (-9925 2950);
FORCEPROP 2 LAST CDS_SEC 1
J 0
(-9925 2950);
DISPLAY 1.021277 (-9925 2950);
DISPLAY INVISIBLE (-9925 2950);
FORCEPROP 1 LASTPIN (-9875 2850) $PN 1
J 2
(-9885 2830);
DISPLAY 0.787234 (-9885 2830);
FORCEPROP 1 LASTPIN (-9875 2650) $PN 2
J 2
(-9885 2630);
DISPLAY 0.787234 (-9885 2630);
FORCEPROP 1 LAST TOLERANCE 10%
J 2
(-9925 2700);
DISPLAY 0.510638 (-9925 2700);
FORCEPROP 1 LAST VALUE 0.1UF
J 2
(-9925 2800);
DISPLAY 0.510638 (-9925 2800);
FORCEPROP 1 LAST VOLTAGE 25V
J 2
(-9925 2750);
DISPLAY 0.510638 (-9925 2750);
FORCEPROP 1 LAST MATERIAL X7R
J 2
(-9925 2650);
DISPLAY 0.510638 (-9925 2650);
FORCEPROP 1 LAST PACK_TYPE 0402
J 2
(-9925 2550);
DISPLAY 0.510638 (-9925 2550);
FORCEPROP 2 LAST CDS_LIB pure_quanta
J 2
(-9875 2750);
PAINT MONO (-9875 2750);
DISPLAY INVISIBLE (-9875 2750);
FORCEPROP 1 LAST PATH I3
J 2
(-9925 2900);
DISPLAY 0.978723 (-9925 2900);
PAINT WHITE (-9925 2900);
DISPLAY INVISIBLE (-9925 2900);
FORCEPROP 1 LAST PART_NUMBER CH4104K1B00
J 2
(-9925 2600);
DISPLAY 0.510638 (-9925 2600);
DISPLAY INVISIBLE (-9925 2600);
FORCEADD OFFPAGE..1
(-4575 3375);
FORCEPROP 2 LAST $XR0 133 
J 0
(-4827 3375);
DISPLAY 0.638298 (-4827 3375);
PAINT MONO (-4827 3375);
FORCEPROP 2 LAST CDS_LIB standard
J 0
(-4575 3375);
DISPLAY INVISIBLE (-4575 3375);
FORCEPROP 1 LAST OFFPAGE TRUE
J 0
(-4250 3250);
DISPLAY 0.872340 (-4250 3250);
PAINT GREEN (-4250 3250);
DISPLAY INVISIBLE (-4250 3250);
FORCEPROP 1 LAST COMMENT_BODY TRUE
J 0
(-4450 3275);
DISPLAY 0.872340 (-4450 3275);
PAINT GREEN (-4450 3275);
DISPLAY INVISIBLE (-4450 3275);
FORCEPROP 2 LAST PATH I30
J 0
(-4825 3425);
DISPLAY 0.680851 (-4825 3425);
DISPLAY INVISIBLE (-4825 3425);
FORCEADD Q_RES..1
(-6725 4250);
FORCEPROP 1 LAST LOCATION R1594
J 0
(-6975 4250);
DISPLAY 0.638298 (-6975 4250);
FORCEPROP 2 LAST $SEC 1
J 0
(-6775 4450);
DISPLAY 0.680851 (-6775 4450);
PAINT MONO (-6775 4450);
DISPLAY INVISIBLE (-6775 4450);
FORCEPROP 2 LAST CDS_SEC 1
J 0
(-6775 4450);
DISPLAY 1.021277 (-6775 4450);
DISPLAY INVISIBLE (-6775 4450);
FORCEPROP 1 LASTPIN (-6825 4250) $PN 1
J 0
(-6813 4262);
DISPLAY 0.787234 (-6813 4262);
FORCEPROP 1 LASTPIN (-6625 4250) $PN 2
J 0
(-6663 4262);
DISPLAY 0.787234 (-6663 4262);
FORCEPROP 1 LAST WATTAGE 1/16W
J 2
(-6550 4375);
DISPLAY 0.510638 (-6550 4375);
FORCEPROP 1 LAST PACK_TYPE 0402LF
J 0
(-6850 4375);
DISPLAY 0.510638 (-6850 4375);
FORCEPROP 1 LAST VALUE 33.2
J 2
(-6525 4250);
DISPLAY 0.510638 (-6525 4250);
FORCEPROP 1 LAST TOLERANCE 1%
J 0
(-6500 4250);
DISPLAY 0.510638 (-6500 4250);
FORCEPROP 1 LAST MATERIAL CHIP
J 0
(-6400 4250);
DISPLAY 0.510638 (-6400 4250);
FORCEPROP 2 LAST CDS_LIB pure_quanta
J 0
(-6725 4250);
PAINT MONO (-6725 4250);
DISPLAY INVISIBLE (-6725 4250);
FORCEPROP 1 LAST PATH I31
J 0
(-6775 4400);
DISPLAY 0.978723 (-6775 4400);
PAINT WHITE (-6775 4400);
DISPLAY INVISIBLE (-6775 4400);
FORCEPROP 1 LAST PART_NUMBER CS03322FB03
J 0
(-6825 4325);
DISPLAY 0.510638 (-6825 4325);
DISPLAY INVISIBLE (-6825 4325);
FORCEADD UNIVERSAL_GND..1
(-7900 4575);
FORCEPROP 3 LASTPIN (-7900 4625) SIG_NAME GND\g
J 0
(-7890 4635);
DISPLAY 0.659574 (-7890 4635);
PAINT MONO (-7890 4635);
DISPLAY INVISIBLE (-7890 4635);
FORCEPROP 2 LAST CDS_LIB pure_quanta_power
J 0
(-7900 4575);
PAINT MONO (-7900 4575);
DISPLAY INVISIBLE (-7900 4575);
FORCEPROP 1 LAST HDL_POWER GND
J 1
(-7875 4500);
DISPLAY 0.872340 (-7875 4500);
PAINT GREEN (-7875 4500);
DISPLAY INVISIBLE (-7875 4500);
FORCEPROP 1 LAST PATH I32
J 0
(-7825 4575);
DISPLAY 0.872340 (-7825 4575);
PAINT AQUA (-7825 4575);
DISPLAY INVISIBLE (-7825 4575);
FORCEADD Q_CAP..1
(-7900 4800);
FORCEPROP 1 LAST LOCATION C36
J 0
(-7850 4900);
DISPLAY 0.978723 (-7850 4900);
FORCEPROP 2 LAST $SEC 1
J 0
(-7850 5000);
DISPLAY 0.680851 (-7850 5000);
PAINT MONO (-7850 5000);
DISPLAY INVISIBLE (-7850 5000);
FORCEPROP 2 LAST CDS_SEC 1
J 0
(-7850 5000);
DISPLAY 1.021277 (-7850 5000);
DISPLAY INVISIBLE (-7850 5000);
FORCEPROP 1 LASTPIN (-7900 4900) $PN 1
J 0
(-7890 4880);
DISPLAY 0.787234 (-7890 4880);
FORCEPROP 1 LASTPIN (-7900 4700) $PN 2
J 0
(-7890 4680);
DISPLAY 0.787234 (-7890 4680);
FORCEPROP 1 LAST VALUE 0.1UF
J 0
(-7850 4850);
DISPLAY 0.510638 (-7850 4850);
FORCEPROP 1 LAST TOLERANCE 10%
J 0
(-7850 4750);
DISPLAY 0.510638 (-7850 4750);
FORCEPROP 1 LAST MATERIAL X7R
J 0
(-7850 4700);
DISPLAY 0.510638 (-7850 4700);
FORCEPROP 1 LAST PACK_TYPE 0402
J 0
(-7850 4600);
DISPLAY 0.510638 (-7850 4600);
FORCEPROP 1 LAST VOLTAGE 25V
J 0
(-7850 4800);
DISPLAY 0.510638 (-7850 4800);
FORCEPROP 2 LAST CDS_LIB pure_quanta
J 2
(-7900 4800);
PAINT MONO (-7900 4800);
DISPLAY INVISIBLE (-7900 4800);
FORCEPROP 1 LAST PATH I33
J 0
(-7850 4950);
DISPLAY 0.978723 (-7850 4950);
PAINT WHITE (-7850 4950);
DISPLAY INVISIBLE (-7850 4950);
FORCEPROP 1 LAST PART_NUMBER CH4104K1B00
J 0
(-7850 4650);
DISPLAY 0.510638 (-7850 4650);
DISPLAY INVISIBLE (-7850 4650);
FORCEADD UNIVERSAL_POWER..1
(-7900 5150);
FORCEPROP 3 LASTPIN (-7900 5100) SIG_NAME P3V3_AUX\g
J 0
(-7890 5110);
DISPLAY 0.659574 (-7890 5110);
PAINT MONO (-7890 5110);
DISPLAY INVISIBLE (-7890 5110);
FORCEPROP 1 LAST HDL_POWER P3V3_AUX
J 1
(-7900 5200);
DISPLAY 0.872340 (-7900 5200);
PAINT GREEN (-7900 5200);
FORCEPROP 2 LAST CDS_LIB pure_quanta_power
J 0
(-7900 5150);
PAINT MONO (-7900 5150);
DISPLAY INVISIBLE (-7900 5150);
FORCEPROP 1 LAST PATH I34
J 0
(-7850 5175);
DISPLAY 0.872340 (-7850 5175);
PAINT AQUA (-7850 5175);
DISPLAY INVISIBLE (-7850 5175);
FORCEADD Q_RES..2
(-7050 4700);
FORCEPROP 1 LAST LOCATION R2488
J 0
(-7005 4825);
DISPLAY 0.978723 (-7005 4825);
FORCEPROP 0 LAST $SEC 1
J 0
(-7000 4875);
DISPLAY 0.680851 (-7000 4875);
PAINT MONO (-7000 4875);
DISPLAY INVISIBLE (-7000 4875);
FORCEPROP 0 LAST CDS_SEC 1
J 0
(-7000 4875);
DISPLAY 1.021277 (-7000 4875);
DISPLAY INVISIBLE (-7000 4875);
FORCEPROP 1 LASTPIN (-7050 4800) $PN 1
J 0
(-7045 4762);
DISPLAY 0.787234 (-7045 4762);
PAINT MONO (-7045 4762);
FORCEPROP 1 LASTPIN (-7050 4600) $PN 2
J 0
(-7045 4610);
DISPLAY 0.787234 (-7045 4610);
PAINT MONO (-7045 4610);
FORCEPROP 1 LAST WATTAGE 1/16W
J 0
(-7010 4675);
DISPLAY 0.787234 (-7010 4675);
FORCEPROP 1 LAST MATERIAL CHIP
J 0
(-7010 4625);
DISPLAY 0.787234 (-7010 4625);
FORCEPROP 1 LAST PACK_TYPE 0402LF
J 0
(-7010 4525);
DISPLAY 0.787234 (-7010 4525);
FORCEPROP 1 LAST TOLERANCE 1%
J 0
(-7005 4725);
DISPLAY 0.787234 (-7005 4725);
FORCEPROP 1 LAST VALUE 4.7K
J 0
(-7005 4775);
DISPLAY 0.787234 (-7005 4775);
FORCEPROP 2 LAST CDS_LIB pure_quanta
J 0
(-7050 4700);
DISPLAY INVISIBLE (-7050 4700);
FORCEPROP 1 LAST PATH I35
J 0
(-7000 4875);
DISPLAY 0.978723 (-7000 4875);
PAINT WHITE (-7000 4875);
DISPLAY INVISIBLE (-7000 4875);
FORCEPROP 1 LAST PART_NUMBER CS24702FB06
J 0
(-7010 4575);
DISPLAY 0.787234 (-7010 4575);
DISPLAY INVISIBLE (-7010 4575);
FORCEADD UNIVERSAL_POWER..1
(-7050 4900);
FORCEPROP 3 LASTPIN (-7050 4850) SIG_NAME P3V3_AUX\g
J 0
(-7040 4860);
DISPLAY 0.659574 (-7040 4860);
PAINT MONO (-7040 4860);
DISPLAY INVISIBLE (-7040 4860);
FORCEPROP 1 LAST HDL_POWER P3V3_AUX
J 1
(-7050 4950);
DISPLAY 0.872340 (-7050 4950);
PAINT GREEN (-7050 4950);
FORCEPROP 2 LAST CDS_LIB pure_quanta_power
J 0
(-7050 4900);
DISPLAY INVISIBLE (-7050 4900);
FORCEPROP 1 LAST PATH I36
J 0
(-7000 4925);
DISPLAY 0.872340 (-7000 4925);
PAINT AQUA (-7000 4925);
DISPLAY INVISIBLE (-7000 4925);
FORCEADD UNIVERSAL_GND..1
(-7725 5500);
FORCEPROP 3 LASTPIN (-7725 5550) SIG_NAME GND\g
J 0
(-7715 5560);
DISPLAY 0.659574 (-7715 5560);
PAINT MONO (-7715 5560);
DISPLAY INVISIBLE (-7715 5560);
FORCEPROP 2 LAST CDS_LIB pure_quanta_power
J 0
(-7725 5500);
PAINT MONO (-7725 5500);
DISPLAY INVISIBLE (-7725 5500);
FORCEPROP 1 LAST HDL_POWER GND
J 1
(-7700 5425);
DISPLAY 0.872340 (-7700 5425);
PAINT GREEN (-7700 5425);
DISPLAY INVISIBLE (-7700 5425);
FORCEPROP 1 LAST PATH I37
J 0
(-7650 5500);
DISPLAY 0.872340 (-7650 5500);
PAINT AQUA (-7650 5500);
DISPLAY INVISIBLE (-7650 5500);
FORCEADD 74LVC1G07GV..1
(-7250 5825);
FORCEPROP 1 LAST LOCATION U104
J 0
(-7375 6150);
DISPLAY 0.723404 (-7375 6150);
PAINT GREEN (-7375 6150);
FORCEPROP 0 LAST $SEC 1
J 0
(-7375 6350);
DISPLAY 0.680851 (-7375 6350);
PAINT MONO (-7375 6350);
DISPLAY INVISIBLE (-7375 6350);
FORCEPROP 0 LAST CDS_SEC 1
J 0
(-7375 6350);
DISPLAY 1.021277 (-7375 6350);
DISPLAY INVISIBLE (-7375 6350);
FORCEPROP 0 LASTPIN (-7525 5825) $PN 2
J 2
(-7535 5835);
DISPLAY 0.680851 (-7535 5835);
PAINT MONO (-7535 5835);
FORCEPROP 0 LASTPIN (-7525 5725) $PN 3
J 2
(-7535 5735);
DISPLAY 0.680851 (-7535 5735);
PAINT MONO (-7535 5735);
FORCEPROP 0 LASTPIN (-7525 5925) $PN 1
J 2
(-7535 5935);
DISPLAY 0.680851 (-7535 5935);
PAINT MONO (-7535 5935);
FORCEPROP 0 LASTPIN (-6975 5925) $PN 5
J 0
(-6965 5935);
DISPLAY 0.680851 (-6965 5935);
PAINT MONO (-6965 5935);
FORCEPROP 0 LASTPIN (-6975 5725) $PN 4
J 0
(-6965 5735);
DISPLAY 0.680851 (-6965 5735);
PAINT MONO (-6965 5735);
FORCEPROP 2 LAST VALUE 74LVC1G07GV
J 0
(-7375 6250);
DISPLAY 0.638298 (-7375 6250);
FORCEPROP 2 LAST PART_TYPE SMLF
J 0
(-7375 6300);
DISPLAY 0.638298 (-7375 6300);
FORCEPROP 1 LAST MATERIAL IC
J 0
(-7369 6007);
DISPLAY 0.723404 (-7369 6007);
PAINT GREEN (-7369 6007);
FORCEPROP 1 LAST CDS_LMAN_SYM_OUTLINE -125,150,125,-150
J 0
(-7250 5825);
DISPLAY 0.468085 (-7250 5825);
PAINT GREEN (-7250 5825);
DISPLAY INVISIBLE (-7250 5825);
FORCEPROP 1 LAST NEEDS_NO_SIZE TRUE
J 0
(-7250 5825);
DISPLAY 0.723404 (-7250 5825);
PAINT GREEN (-7250 5825);
DISPLAY INVISIBLE (-7250 5825);
FORCEPROP 2 LAST CDS_LIB pure_quanta
J 0
(-7250 5825);
DISPLAY INVISIBLE (-7250 5825);
FORCEPROP 1 LAST PATH I38
J 0
(-7250 5825);
DISPLAY 0.723404 (-7250 5825);
PAINT GREEN (-7250 5825);
DISPLAY INVISIBLE (-7250 5825);
FORCEPROP 1 LAST PART_NUMBER AL1G0007001
J 0
(-7375 6075);
DISPLAY 0.723404 (-7375 6075);
PAINT GREEN (-7375 6075);
DISPLAY INVISIBLE (-7375 6075);
FORCEADD UNIVERSAL_GND..1
(-6575 5975);
FORCEPROP 3 LASTPIN (-6575 6025) SIG_NAME GND\g
J 0
(-6565 6035);
DISPLAY 0.659574 (-6565 6035);
PAINT MONO (-6565 6035);
DISPLAY INVISIBLE (-6565 6035);
FORCEPROP 2 LAST CDS_LIB pure_quanta_power
J 0
(-6575 5975);
PAINT MONO (-6575 5975);
DISPLAY INVISIBLE (-6575 5975);
FORCEPROP 1 LAST HDL_POWER GND
J 1
(-6550 5900);
DISPLAY 0.872340 (-6550 5900);
PAINT GREEN (-6550 5900);
DISPLAY INVISIBLE (-6550 5900);
FORCEPROP 1 LAST PATH I39
J 0
(-6500 5975);
DISPLAY 0.872340 (-6500 5975);
PAINT AQUA (-6500 5975);
DISPLAY INVISIBLE (-6500 5975);
FORCEADD Q_OSC4P..1
(-9275 2450);
FORCEPROP 1 LAST LOCATION OSC1
J 0
(-9450 2680);
DISPLAY 0.723404 (-9450 2680);
PAINT GREEN (-9450 2680);
FORCEPROP 0 LAST $SEC 1
J 0
(-9450 2825);
DISPLAY 0.680851 (-9450 2825);
PAINT MONO (-9450 2825);
DISPLAY INVISIBLE (-9450 2825);
FORCEPROP 0 LAST CDS_SEC 1
J 0
(-9450 2825);
DISPLAY 1.021277 (-9450 2825);
DISPLAY INVISIBLE (-9450 2825);
FORCEPROP 0 LASTPIN (-8950 2375) $PN 2
J 0
(-8940 2385);
DISPLAY 0.680851 (-8940 2385);
PAINT MONO (-8940 2385);
FORCEPROP 0 LASTPIN (-9600 2375) $PN 1
J 2
(-9610 2385);
DISPLAY 0.680851 (-9610 2385);
PAINT MONO (-9610 2385);
FORCEPROP 0 LASTPIN (-8950 2525) $PN 3
J 0
(-8940 2535);
DISPLAY 0.680851 (-8940 2535);
PAINT MONO (-8940 2535);
FORCEPROP 0 LASTPIN (-9600 2525) $PN 4
J 2
(-9610 2535);
DISPLAY 0.680851 (-9610 2535);
PAINT MONO (-9610 2535);
FORCEPROP 2 LAST PACK_TYPE SMLF
J 0
(-9450 2725);
DISPLAY 1.021277 (-9450 2725);
FORCEPROP 2 LAST VALUE 50MHZ
J 0
(-9450 2775);
DISPLAY 1.021277 (-9450 2775);
FORCEPROP 1 LAST MATERIAL OSC
J 0
(-9450 2585);
DISPLAY 0.723404 (-9450 2585);
PAINT GREEN (-9450 2585);
FORCEPROP 2 LAST CDS_LIB pure_quanta
J 0
(-9275 2450);
DISPLAY INVISIBLE (-9275 2450);
FORCEPROP 1 LAST NEEDS_NO_SIZE TRUE
J 0
(-9275 2450);
DISPLAY 0.468085 (-9275 2450);
PAINT GREEN (-9275 2450);
DISPLAY INVISIBLE (-9275 2450);
FORCEPROP 1 LAST PATH I4
J 0
(-9125 2585);
DISPLAY 0.723404 (-9125 2585);
PAINT GREEN (-9125 2585);
DISPLAY INVISIBLE (-9125 2585);
FORCEPROP 1 LAST PART_NUMBER BF650000032
J 0
(-9450 2630);
DISPLAY 0.723404 (-9450 2630);
PAINT GREEN (-9450 2630);
DISPLAY INVISIBLE (-9450 2630);
FORCEADD Q_CAP..1
(-6575 6200);
FORCEPROP 1 LAST LOCATION C72
J 0
(-6525 6300);
DISPLAY 0.978723 (-6525 6300);
FORCEPROP 2 LAST $SEC 1
J 0
(-6525 6400);
DISPLAY 0.680851 (-6525 6400);
PAINT MONO (-6525 6400);
DISPLAY INVISIBLE (-6525 6400);
FORCEPROP 2 LAST CDS_SEC 1
J 0
(-6525 6400);
DISPLAY 1.021277 (-6525 6400);
DISPLAY INVISIBLE (-6525 6400);
FORCEPROP 1 LASTPIN (-6575 6300) $PN 1
J 0
(-6565 6280);
DISPLAY 0.787234 (-6565 6280);
FORCEPROP 1 LASTPIN (-6575 6100) $PN 2
J 0
(-6565 6080);
DISPLAY 0.787234 (-6565 6080);
FORCEPROP 1 LAST PACK_TYPE 0402
J 0
(-6525 6000);
DISPLAY 0.510638 (-6525 6000);
FORCEPROP 1 LAST MATERIAL X7R
J 0
(-6525 6100);
DISPLAY 0.510638 (-6525 6100);
FORCEPROP 1 LAST TOLERANCE 10%
J 0
(-6525 6150);
DISPLAY 0.510638 (-6525 6150);
FORCEPROP 1 LAST VOLTAGE 25V
J 0
(-6525 6200);
DISPLAY 0.510638 (-6525 6200);
FORCEPROP 1 LAST VALUE 0.1UF
J 0
(-6525 6250);
DISPLAY 0.510638 (-6525 6250);
FORCEPROP 2 LAST CDS_LIB pure_quanta
J 2
(-6575 6200);
PAINT MONO (-6575 6200);
DISPLAY INVISIBLE (-6575 6200);
FORCEPROP 1 LAST PATH I40
J 0
(-6525 6350);
DISPLAY 0.978723 (-6525 6350);
PAINT WHITE (-6525 6350);
DISPLAY INVISIBLE (-6525 6350);
FORCEPROP 1 LAST PART_NUMBER CH4104K1B00
J 0
(-6525 6050);
DISPLAY 0.510638 (-6525 6050);
DISPLAY INVISIBLE (-6525 6050);
FORCEADD UNIVERSAL_POWER..1
(-6775 6475);
FORCEPROP 3 LASTPIN (-6775 6425) SIG_NAME P3V3_AUX\g
J 0
(-6765 6435);
DISPLAY 0.659574 (-6765 6435);
PAINT MONO (-6765 6435);
DISPLAY INVISIBLE (-6765 6435);
FORCEPROP 1 LAST HDL_POWER P3V3_AUX
J 1
(-6775 6525);
DISPLAY 0.872340 (-6775 6525);
PAINT GREEN (-6775 6525);
FORCEPROP 2 LAST CDS_LIB pure_quanta_power
J 0
(-6775 6475);
PAINT MONO (-6775 6475);
DISPLAY INVISIBLE (-6775 6475);
FORCEPROP 1 LAST PATH I41
J 0
(-6725 6500);
DISPLAY 0.872340 (-6725 6500);
PAINT AQUA (-6725 6500);
DISPLAY INVISIBLE (-6725 6500);
FORCEADD Q_RES..2
(-5875 6100);
FORCEPROP 1 LAST LOCATION R53
J 0
(-5830 6225);
DISPLAY 0.787234 (-5830 6225);
FORCEPROP 2 LAST $SEC 1
J 0
(-5825 6325);
DISPLAY 0.680851 (-5825 6325);
PAINT MONO (-5825 6325);
DISPLAY INVISIBLE (-5825 6325);
FORCEPROP 2 LAST CDS_SEC 1
J 0
(-5825 6325);
DISPLAY 1.021277 (-5825 6325);
DISPLAY INVISIBLE (-5825 6325);
FORCEPROP 1 LASTPIN (-5875 6200) $PN 1
J 0
(-5870 6162);
DISPLAY 0.787234 (-5870 6162);
FORCEPROP 1 LASTPIN (-5875 6000) $PN 2
J 0
(-5870 6010);
DISPLAY 0.787234 (-5870 6010);
FORCEPROP 1 LAST TOLERANCE 1%
J 0
(-5830 6125);
DISPLAY 0.787234 (-5830 6125);
FORCEPROP 1 LAST PACK_TYPE 0402LF
J 0
(-5835 5925);
DISPLAY 0.787234 (-5835 5925);
FORCEPROP 1 LAST MATERIAL CHIP
J 0
(-5835 6025);
DISPLAY 0.787234 (-5835 6025);
PAINT RED (-5835 6025);
FORCEPROP 1 LAST VALUE 4.7K
J 0
(-5830 6175);
DISPLAY 0.787234 (-5830 6175);
FORCEPROP 1 LAST WATTAGE 1/16W
J 0
(-5835 6075);
DISPLAY 0.787234 (-5835 6075);
FORCEPROP 2 LAST CDS_LIB pure_quanta
J 0
(-5875 6100);
PAINT MONO (-5875 6100);
DISPLAY INVISIBLE (-5875 6100);
FORCEPROP 1 LAST PATH I42
J 0
(-5825 6275);
DISPLAY 0.978723 (-5825 6275);
PAINT WHITE (-5825 6275);
DISPLAY INVISIBLE (-5825 6275);
FORCEPROP 1 LAST PART_NUMBER CS24702FB06
J 0
(-5835 5975);
DISPLAY 0.787234 (-5835 5975);
DISPLAY INVISIBLE (-5835 5975);
FORCEADD UNIVERSAL_POWER..1
(-5875 6300);
FORCEPROP 3 LASTPIN (-5875 6250) SIG_NAME P3V3_AUX\g
J 0
(-5865 6260);
DISPLAY 0.659574 (-5865 6260);
PAINT MONO (-5865 6260);
DISPLAY INVISIBLE (-5865 6260);
FORCEPROP 1 LAST HDL_POWER P3V3_AUX
J 1
(-5875 6350);
DISPLAY 0.872340 (-5875 6350);
PAINT GREEN (-5875 6350);
FORCEPROP 2 LAST CDS_LIB pure_quanta_power
J 0
(-5875 6300);
PAINT MONO (-5875 6300);
DISPLAY INVISIBLE (-5875 6300);
FORCEPROP 1 LAST PATH I43
J 0
(-5825 6325);
DISPLAY 0.872340 (-5825 6325);
PAINT AQUA (-5825 6325);
DISPLAY INVISIBLE (-5825 6325);
FORCEADD Q_RES..1
(-5325 5725);
FORCEPROP 1 LAST LOCATION R1595
J 0
(-5600 5725);
DISPLAY 0.638298 (-5600 5725);
FORCEPROP 2 LAST $SEC 1
J 0
(-5375 5925);
DISPLAY 0.680851 (-5375 5925);
PAINT MONO (-5375 5925);
DISPLAY INVISIBLE (-5375 5925);
FORCEPROP 2 LAST CDS_SEC 1
J 0
(-5375 5925);
DISPLAY 1.021277 (-5375 5925);
DISPLAY INVISIBLE (-5375 5925);
FORCEPROP 1 LASTPIN (-5425 5725) $PN 1
J 0
(-5413 5737);
DISPLAY 0.787234 (-5413 5737);
FORCEPROP 1 LASTPIN (-5225 5725) $PN 2
J 0
(-5263 5737);
DISPLAY 0.787234 (-5263 5737);
FORCEPROP 1 LAST TOLERANCE 1%
J 0
(-5100 5725);
DISPLAY 0.510638 (-5100 5725);
FORCEPROP 1 LAST WATTAGE 1/16W
J 2
(-5150 5850);
DISPLAY 0.510638 (-5150 5850);
FORCEPROP 1 LAST PACK_TYPE 0402LF
J 0
(-5025 5725);
DISPLAY 0.510638 (-5025 5725);
FORCEPROP 1 LAST VALUE 33.2
J 2
(-5125 5725);
DISPLAY 0.510638 (-5125 5725);
FORCEPROP 1 LAST MATERIAL CHIP
J 0
(-5425 5850);
DISPLAY 0.510638 (-5425 5850);
FORCEPROP 2 LAST CDS_LIB pure_quanta
J 0
(-5325 5725);
PAINT MONO (-5325 5725);
DISPLAY INVISIBLE (-5325 5725);
FORCEPROP 1 LAST PATH I44
J 0
(-5375 5875);
DISPLAY 0.978723 (-5375 5875);
PAINT WHITE (-5375 5875);
DISPLAY INVISIBLE (-5375 5875);
FORCEPROP 1 LAST PART_NUMBER CS03322FB03
J 0
(-5425 5800);
DISPLAY 0.510638 (-5425 5800);
DISPLAY INVISIBLE (-5425 5800);
FORCEADD UNIVERSAL_POWER..1
(-4525 4800);
FORCEPROP 3 LASTPIN (-4525 4750) SIG_NAME P3V3_AUX\g
J 0
(-4515 4760);
DISPLAY 0.659574 (-4515 4760);
PAINT MONO (-4515 4760);
DISPLAY INVISIBLE (-4515 4760);
FORCEPROP 1 LAST HDL_POWER P3V3_AUX
J 1
(-4525 4850);
DISPLAY 0.872340 (-4525 4850);
PAINT GREEN (-4525 4850);
FORCEPROP 2 LAST CDS_LIB pure_quanta_power
J 0
(-4525 4800);
DISPLAY INVISIBLE (-4525 4800);
FORCEPROP 1 LAST PATH I45
J 0
(-4475 4825);
DISPLAY 0.872340 (-4475 4825);
PAINT AQUA (-4475 4825);
DISPLAY INVISIBLE (-4475 4825);
FORCEADD UNIVERSAL_GND..1
(-4325 4300);
FORCEPROP 3 LASTPIN (-4325 4350) SIG_NAME GND\g
J 0
(-4315 4360);
DISPLAY 0.659574 (-4315 4360);
PAINT MONO (-4315 4360);
DISPLAY INVISIBLE (-4315 4360);
FORCEPROP 2 LAST CDS_LIB pure_quanta_power
J 0
(-4325 4300);
DISPLAY INVISIBLE (-4325 4300);
FORCEPROP 1 LAST HDL_POWER GND
J 1
(-4300 4225);
DISPLAY 0.872340 (-4300 4225);
PAINT GREEN (-4300 4225);
DISPLAY INVISIBLE (-4300 4225);
FORCEPROP 1 LAST PATH I46
J 0
(-4250 4300);
DISPLAY 0.872340 (-4250 4300);
PAINT AQUA (-4250 4300);
DISPLAY INVISIBLE (-4250 4300);
FORCEADD Q_CAP..1
(-4325 4525);
FORCEPROP 1 LAST LOCATION C1663
J 0
(-4275 4625);
DISPLAY 0.978723 (-4275 4625);
FORCEPROP 0 LAST $SEC 1
J 0
(-4275 4675);
DISPLAY 0.680851 (-4275 4675);
PAINT MONO (-4275 4675);
DISPLAY INVISIBLE (-4275 4675);
FORCEPROP 0 LAST CDS_SEC 1
J 0
(-4275 4675);
DISPLAY 1.021277 (-4275 4675);
DISPLAY INVISIBLE (-4275 4675);
FORCEPROP 1 LASTPIN (-4325 4625) $PN 1
J 0
(-4315 4605);
DISPLAY 0.787234 (-4315 4605);
PAINT MONO (-4315 4605);
FORCEPROP 1 LASTPIN (-4325 4425) $PN 2
J 0
(-4315 4405);
DISPLAY 0.787234 (-4315 4405);
PAINT MONO (-4315 4405);
FORCEPROP 1 LAST TOLERANCE 10%
J 0
(-4275 4475);
DISPLAY 0.510638 (-4275 4475);
FORCEPROP 1 LAST VALUE 0.1UF
J 0
(-4275 4575);
DISPLAY 0.510638 (-4275 4575);
FORCEPROP 1 LAST VOLTAGE 25V
J 0
(-4275 4525);
DISPLAY 0.510638 (-4275 4525);
FORCEPROP 1 LAST MATERIAL X7R
J 0
(-4275 4425);
DISPLAY 0.510638 (-4275 4425);
FORCEPROP 1 LAST PACK_TYPE 0402
J 0
(-4275 4325);
DISPLAY 0.510638 (-4275 4325);
FORCEPROP 2 LAST CDS_LIB pure_quanta
J 0
(-4325 4525);
DISPLAY INVISIBLE (-4325 4525);
FORCEPROP 1 LAST PATH I47
J 0
(-4275 4675);
DISPLAY 0.978723 (-4275 4675);
PAINT WHITE (-4275 4675);
DISPLAY INVISIBLE (-4275 4675);
FORCEPROP 1 LAST PART_NUMBER CH4104K1B00
J 0
(-4275 4375);
DISPLAY 0.510638 (-4275 4375);
DISPLAY INVISIBLE (-4275 4375);
FORCEADD OFFPAGE..2
(-4075 5725);
FORCEPROP 2 LAST $XR0 131 
J 0
(-3886 5725);
DISPLAY 0.638298 (-3886 5725);
PAINT MONO (-3886 5725);
FORCEPROP 2 LAST CDS_LIB standard
J 0
(-4075 5725);
PAINT MONO (-4075 5725);
DISPLAY INVISIBLE (-4075 5725);
FORCEPROP 1 LAST OFFPAGE TRUE
J 0
(-3750 5600);
DISPLAY 0.872340 (-3750 5600);
PAINT GREEN (-3750 5600);
DISPLAY INVISIBLE (-3750 5600);
FORCEPROP 1 LAST COMMENT_BODY TRUE
J 0
(-4120 5630);
DISPLAY 0.872340 (-4120 5630);
PAINT GREEN (-4120 5630);
DISPLAY INVISIBLE (-4120 5630);
FORCEPROP 2 LAST PATH I48
J 0
(-3875 5775);
DISPLAY 0.680851 (-3875 5775);
DISPLAY INVISIBLE (-3875 5775);
FORCEADD UNIVERSAL_GND..1
(-3600 3025);
FORCEPROP 3 LASTPIN (-3600 3075) SIG_NAME GND\g
J 0
(-3590 3085);
DISPLAY 0.659574 (-3590 3085);
PAINT MONO (-3590 3085);
DISPLAY INVISIBLE (-3590 3085);
FORCEPROP 2 LAST CDS_LIB pure_quanta_power
J 0
(-3600 3025);
DISPLAY INVISIBLE (-3600 3025);
FORCEPROP 1 LAST HDL_POWER GND
J 1
(-3575 2950);
DISPLAY 0.872340 (-3575 2950);
PAINT GREEN (-3575 2950);
DISPLAY INVISIBLE (-3575 2950);
FORCEPROP 1 LAST PATH I49
J 0
(-3525 3025);
DISPLAY 0.872340 (-3525 3025);
PAINT AQUA (-3525 3025);
DISPLAY INVISIBLE (-3525 3025);
FORCEADD UNIVERSAL_POWER..1
(-9775 3125);
FORCEPROP 3 LASTPIN (-9775 3075) SIG_NAME P3V3_AUX\g
J 0
(-9765 3085);
DISPLAY 0.659574 (-9765 3085);
PAINT MONO (-9765 3085);
DISPLAY INVISIBLE (-9765 3085);
FORCEPROP 1 LAST HDL_POWER P3V3_AUX
J 1
(-9775 3175);
DISPLAY 0.872340 (-9775 3175);
PAINT GREEN (-9775 3175);
FORCEPROP 2 LAST CDS_LIB pure_quanta_power
J 0
(-9775 3125);
PAINT MONO (-9775 3125);
DISPLAY INVISIBLE (-9775 3125);
FORCEPROP 1 LAST PATH I5
J 0
(-9725 3150);
DISPLAY 0.872340 (-9725 3150);
PAINT AQUA (-9725 3150);
DISPLAY INVISIBLE (-9725 3150);
FORCEADD Q_RES..1
(-3475 4150);
FORCEPROP 1 LAST LOCATION R2489
J 0
(-3725 4150);
DISPLAY 0.638298 (-3725 4150);
FORCEPROP 0 LAST $SEC 1
J 0
(-3300 4300);
DISPLAY 0.680851 (-3300 4300);
PAINT MONO (-3300 4300);
DISPLAY INVISIBLE (-3300 4300);
FORCEPROP 0 LAST CDS_SEC 1
J 0
(-3300 4300);
DISPLAY 1.021277 (-3300 4300);
DISPLAY INVISIBLE (-3300 4300);
FORCEPROP 1 LASTPIN (-3575 4150) $PN 1
J 0
(-3563 4162);
DISPLAY 0.787234 (-3563 4162);
PAINT MONO (-3563 4162);
FORCEPROP 1 LASTPIN (-3375 4150) $PN 2
J 0
(-3413 4162);
DISPLAY 0.787234 (-3413 4162);
PAINT MONO (-3413 4162);
FORCEPROP 1 LAST MATERIAL CHIP
J 0
(-3175 4150);
DISPLAY 0.510638 (-3175 4150);
FORCEPROP 1 LAST VALUE 33.2
J 2
(-3275 4150);
DISPLAY 0.510638 (-3275 4150);
FORCEPROP 1 LAST WATTAGE 1/16W
J 2
(-3300 4275);
DISPLAY 0.510638 (-3300 4275);
FORCEPROP 1 LAST TOLERANCE 1%
J 0
(-3250 4150);
DISPLAY 0.510638 (-3250 4150);
FORCEPROP 1 LAST PACK_TYPE 0402LF
J 0
(-3600 4275);
DISPLAY 0.510638 (-3600 4275);
FORCEPROP 2 LAST CDS_LIB pure_quanta
J 0
(-3475 4150);
DISPLAY INVISIBLE (-3475 4150);
FORCEPROP 1 LAST PATH I50
J 0
(-3525 4300);
DISPLAY 0.978723 (-3525 4300);
PAINT WHITE (-3525 4300);
DISPLAY INVISIBLE (-3525 4300);
FORCEPROP 1 LAST PART_NUMBER CS03322FB03
J 0
(-3575 4225);
DISPLAY 0.510638 (-3575 4225);
DISPLAY INVISIBLE (-3575 4225);
FORCEADD OFFPAGE..1
R 2
(-2100 3225);
FORCEPROP 2 LAST $XR0 132 
J 0
(-1914 3225);
DISPLAY 0.638298 (-1914 3225);
PAINT MONO (-1914 3225);
FORCEPROP 2 LAST CDS_LIB standard
J 2
(-2100 3225);
DISPLAY INVISIBLE (-2100 3225);
FORCEPROP 1 LAST OFFPAGE TRUE
J 2
(-2425 3100);
DISPLAY 0.872340 (-2425 3100);
PAINT GREEN (-2425 3100);
DISPLAY INVISIBLE (-2425 3100);
FORCEPROP 1 LAST COMMENT_BODY TRUE
J 2
(-2225 3125);
DISPLAY 0.872340 (-2225 3125);
PAINT GREEN (-2225 3125);
DISPLAY INVISIBLE (-2225 3125);
FORCEPROP 2 LAST PATH I51
J 0
(-1900 3275);
DISPLAY 0.680851 (-1900 3275);
DISPLAY INVISIBLE (-1900 3275);
FORCEADD UNIVERSAL_GND..1
(-2525 3325);
FORCEPROP 3 LASTPIN (-2525 3375) SIG_NAME GND\g
J 0
(-2515 3385);
DISPLAY 0.659574 (-2515 3385);
PAINT MONO (-2515 3385);
DISPLAY INVISIBLE (-2515 3385);
FORCEPROP 2 LAST CDS_LIB pure_quanta_power
J 0
(-2525 3325);
DISPLAY INVISIBLE (-2525 3325);
FORCEPROP 1 LAST HDL_POWER GND
J 1
(-2500 3250);
DISPLAY 0.872340 (-2500 3250);
PAINT GREEN (-2500 3250);
DISPLAY INVISIBLE (-2500 3250);
FORCEPROP 1 LAST PATH I52
J 0
(-2450 3325);
DISPLAY 0.872340 (-2450 3325);
PAINT AQUA (-2450 3325);
DISPLAY INVISIBLE (-2450 3325);
FORCEADD Q_CAP..1
(-2525 3550);
FORCEPROP 1 LAST LOCATION C2344
J 0
(-2475 3650);
DISPLAY 0.978723 (-2475 3650);
FORCEPROP 0 LAST $SEC 1
J 0
(-2475 3700);
DISPLAY 0.680851 (-2475 3700);
PAINT MONO (-2475 3700);
DISPLAY INVISIBLE (-2475 3700);
FORCEPROP 0 LAST CDS_SEC 1
J 0
(-2475 3700);
DISPLAY 1.021277 (-2475 3700);
DISPLAY INVISIBLE (-2475 3700);
FORCEPROP 1 LASTPIN (-2525 3650) $PN 1
J 0
(-2515 3630);
DISPLAY 0.787234 (-2515 3630);
PAINT MONO (-2515 3630);
FORCEPROP 1 LASTPIN (-2525 3450) $PN 2
J 0
(-2515 3430);
DISPLAY 0.787234 (-2515 3430);
PAINT MONO (-2515 3430);
FORCEPROP 1 LAST PACK_TYPE 0402
J 0
(-2475 3350);
DISPLAY 0.510638 (-2475 3350);
FORCEPROP 1 LAST VOLTAGE 25V
J 0
(-2475 3550);
DISPLAY 0.510638 (-2475 3550);
FORCEPROP 1 LAST TOLERANCE 10%
J 0
(-2475 3500);
DISPLAY 0.510638 (-2475 3500);
FORCEPROP 1 LAST VALUE 0.1UF
J 0
(-2475 3600);
DISPLAY 0.510638 (-2475 3600);
FORCEPROP 1 LAST MATERIAL X7R
J 0
(-2475 3450);
DISPLAY 0.510638 (-2475 3450);
FORCEPROP 2 LAST CDS_LIB pure_quanta
J 0
(-2525 3550);
DISPLAY INVISIBLE (-2525 3550);
FORCEPROP 1 LAST PATH I53
J 0
(-2475 3700);
DISPLAY 0.978723 (-2475 3700);
PAINT WHITE (-2475 3700);
DISPLAY INVISIBLE (-2475 3700);
FORCEPROP 1 LAST PART_NUMBER CH4104K1B00
J 0
(-2475 3400);
DISPLAY 0.510638 (-2475 3400);
DISPLAY INVISIBLE (-2475 3400);
FORCEADD UNIVERSAL_POWER..1
(-2725 3825);
FORCEPROP 3 LASTPIN (-2725 3775) SIG_NAME P3V3_AUX\g
J 0
(-2715 3785);
DISPLAY 0.659574 (-2715 3785);
PAINT MONO (-2715 3785);
DISPLAY INVISIBLE (-2715 3785);
FORCEPROP 1 LAST HDL_POWER P3V3_AUX
J 1
(-2725 3875);
DISPLAY 0.872340 (-2725 3875);
PAINT GREEN (-2725 3875);
FORCEPROP 2 LAST CDS_LIB pure_quanta_power
J 0
(-2725 3825);
DISPLAY INVISIBLE (-2725 3825);
FORCEPROP 1 LAST PATH I54
J 0
(-2675 3850);
DISPLAY 0.872340 (-2675 3850);
PAINT AQUA (-2675 3850);
DISPLAY INVISIBLE (-2675 3850);
FORCEADD OFFPAGE..2
(-2150 4150);
FORCEPROP 2 LAST $XR0 155 
J 0
(-1961 4150);
DISPLAY 0.638298 (-1961 4150);
PAINT MONO (-1961 4150);
FORCEPROP 2 LAST CDS_LIB standard
J 0
(-2150 4150);
PAINT MONO (-2150 4150);
DISPLAY INVISIBLE (-2150 4150);
FORCEPROP 1 LAST OFFPAGE TRUE
J 0
(-1825 4025);
DISPLAY 0.872340 (-1825 4025);
PAINT GREEN (-1825 4025);
DISPLAY INVISIBLE (-1825 4025);
FORCEPROP 1 LAST COMMENT_BODY TRUE
J 0
(-2195 4055);
DISPLAY 0.872340 (-2195 4055);
PAINT GREEN (-2195 4055);
DISPLAY INVISIBLE (-2195 4055);
FORCEPROP 2 LAST PATH I55
J 0
(-1700 4200);
DISPLAY 0.680851 (-1700 4200);
DISPLAY INVISIBLE (-1700 4200);
FORCEADD Q_RES..2
(-3775 4600);
FORCEPROP 1 LAST LOCATION R2487
J 0
(-3730 4725);
DISPLAY 0.978723 (-3730 4725);
FORCEPROP 0 LAST $SEC 1
J 0
(-3725 4775);
DISPLAY 0.680851 (-3725 4775);
PAINT MONO (-3725 4775);
DISPLAY INVISIBLE (-3725 4775);
FORCEPROP 0 LAST CDS_SEC 1
J 0
(-3725 4775);
DISPLAY 1.021277 (-3725 4775);
DISPLAY INVISIBLE (-3725 4775);
FORCEPROP 1 LASTPIN (-3775 4700) $PN 1
J 0
(-3770 4662);
DISPLAY 0.787234 (-3770 4662);
PAINT MONO (-3770 4662);
FORCEPROP 1 LASTPIN (-3775 4500) $PN 2
J 0
(-3770 4510);
DISPLAY 0.787234 (-3770 4510);
PAINT MONO (-3770 4510);
FORCEPROP 1 LAST MATERIAL EMPTY
J 0
(-3735 4525);
DISPLAY 0.638298 (-3735 4525);
PAINT RED (-3735 4525);
FORCEPROP 1 LAST PACK_TYPE 0402LF
J 0
(-3735 4425);
DISPLAY 0.638298 (-3735 4425);
FORCEPROP 1 LAST TOLERANCE 1%
J 0
(-3730 4625);
DISPLAY 0.638298 (-3730 4625);
FORCEPROP 1 LAST WATTAGE 1/16W
J 0
(-3735 4575);
DISPLAY 0.638298 (-3735 4575);
FORCEPROP 1 LAST VALUE 4.7K
J 0
(-3730 4675);
DISPLAY 0.638298 (-3730 4675);
FORCEPROP 2 LAST CDS_LIB pure_quanta
J 0
(-3775 4600);
DISPLAY INVISIBLE (-3775 4600);
FORCEPROP 1 LAST PATH I56
J 0
(-3725 4775);
DISPLAY 0.978723 (-3725 4775);
PAINT WHITE (-3725 4775);
DISPLAY INVISIBLE (-3725 4775);
FORCEPROP 1 LAST PART_NUMBER CS24702FB06
J 0
(-3735 4475);
DISPLAY 0.638298 (-3735 4475);
DISPLAY INVISIBLE (-3735 4475);
FORCEADD UNIVERSAL_POWER..1
(-3775 4800);
FORCEPROP 3 LASTPIN (-3775 4750) SIG_NAME P3V3_AUX\g
J 0
(-3765 4760);
DISPLAY 0.659574 (-3765 4760);
PAINT MONO (-3765 4760);
DISPLAY INVISIBLE (-3765 4760);
FORCEPROP 1 LAST HDL_POWER P3V3_AUX
J 1
(-3775 4850);
DISPLAY 0.872340 (-3775 4850);
PAINT GREEN (-3775 4850);
FORCEPROP 2 LAST CDS_LIB pure_quanta_power
J 0
(-3775 4800);
DISPLAY INVISIBLE (-3775 4800);
FORCEPROP 1 LAST PATH I57
J 0
(-3725 4825);
DISPLAY 0.872340 (-3725 4825);
PAINT AQUA (-3725 4825);
DISPLAY INVISIBLE (-3725 4825);
FORCEADD OFFPAGE..1
(-9125 7025);
FORCEPROP 2 LAST $XR0 136 
J 0
(-9377 7025);
DISPLAY 0.638298 (-9377 7025);
PAINT MONO (-9377 7025);
FORCEPROP 2 LAST CDS_LIB standard
J 0
(-9125 7025);
PAINT MONO (-9125 7025);
DISPLAY INVISIBLE (-9125 7025);
FORCEPROP 1 LAST OFFPAGE TRUE
J 0
(-8800 6900);
DISPLAY 0.872340 (-8800 6900);
PAINT GREEN (-8800 6900);
DISPLAY INVISIBLE (-8800 6900);
FORCEPROP 1 LAST COMMENT_BODY TRUE
J 0
(-9000 6925);
DISPLAY 0.872340 (-9000 6925);
PAINT GREEN (-9000 6925);
DISPLAY INVISIBLE (-9000 6925);
FORCEPROP 2 LAST PATH I59
J 0
(-9375 7075);
DISPLAY 0.680851 (-9375 7075);
DISPLAY INVISIBLE (-9375 7075);
FORCEADD UNIVERSAL_GND..1
(-8825 2250);
FORCEPROP 3 LASTPIN (-8825 2300) SIG_NAME GND\g
J 0
(-8815 2310);
DISPLAY 0.659574 (-8815 2310);
PAINT MONO (-8815 2310);
DISPLAY INVISIBLE (-8815 2310);
FORCEPROP 2 LAST ROOM IO_SLOT
J 1
(-9050 2325);
DISPLAY 0.744681 (-9050 2325);
FORCEPROP 2 LAST CDS_LIB pure_quanta_power
J 0
(-8825 2250);
PAINT MONO (-8825 2250);
DISPLAY INVISIBLE (-8825 2250);
FORCEPROP 1 LAST HDL_POWER GND
J 1
(-8800 2175);
DISPLAY 0.872340 (-8800 2175);
PAINT GREEN (-8800 2175);
DISPLAY INVISIBLE (-8800 2175);
FORCEPROP 1 LAST PATH I6
J 0
(-8750 2250);
DISPLAY 0.872340 (-8750 2250);
PAINT AQUA (-8750 2250);
DISPLAY INVISIBLE (-8750 2250);
FORCEADD UNIVERSAL_GND..1
(-8475 7125);
FORCEPROP 3 LASTPIN (-8475 7175) SIG_NAME GND\g
J 0
(-8465 7185);
DISPLAY 0.659574 (-8465 7185);
PAINT MONO (-8465 7185);
DISPLAY INVISIBLE (-8465 7185);
FORCEPROP 2 LAST CDS_LIB pure_quanta_power
J 0
(-8475 7125);
PAINT MONO (-8475 7125);
DISPLAY INVISIBLE (-8475 7125);
FORCEPROP 1 LAST HDL_POWER GND
J 1
(-8450 7050);
DISPLAY 0.872340 (-8450 7050);
PAINT GREEN (-8450 7050);
DISPLAY INVISIBLE (-8450 7050);
FORCEPROP 1 LAST PATH I60
J 0
(-8400 7125);
DISPLAY 0.872340 (-8400 7125);
PAINT AQUA (-8400 7125);
DISPLAY INVISIBLE (-8400 7125);
FORCEADD Q_CAP..1
R 2
(-8475 7350);
FORCEPROP 1 LAST LOCATION C10
J 2
(-8525 7450);
DISPLAY 0.978723 (-8525 7450);
FORCEPROP 2 LAST $SEC 1
J 0
(-8525 7550);
DISPLAY 0.680851 (-8525 7550);
PAINT MONO (-8525 7550);
DISPLAY INVISIBLE (-8525 7550);
FORCEPROP 2 LAST CDS_SEC 1
J 0
(-8525 7550);
DISPLAY 1.021277 (-8525 7550);
DISPLAY INVISIBLE (-8525 7550);
FORCEPROP 1 LASTPIN (-8475 7450) $PN 1
J 2
(-8485 7430);
DISPLAY 0.787234 (-8485 7430);
FORCEPROP 1 LASTPIN (-8475 7250) $PN 2
J 2
(-8485 7230);
DISPLAY 0.787234 (-8485 7230);
FORCEPROP 1 LAST TOLERANCE 10%
J 2
(-8525 7300);
DISPLAY 0.510638 (-8525 7300);
FORCEPROP 1 LAST VOLTAGE 25V
J 2
(-8525 7350);
DISPLAY 0.510638 (-8525 7350);
FORCEPROP 1 LAST PACK_TYPE 0402
J 2
(-8525 7150);
DISPLAY 0.510638 (-8525 7150);
FORCEPROP 1 LAST VALUE 0.1UF
J 2
(-8525 7400);
DISPLAY 0.510638 (-8525 7400);
FORCEPROP 1 LAST MATERIAL X7R
J 2
(-8525 7250);
DISPLAY 0.510638 (-8525 7250);
FORCEPROP 2 LAST CDS_LIB pure_quanta
J 0
(-8475 7350);
PAINT MONO (-8475 7350);
DISPLAY INVISIBLE (-8475 7350);
FORCEPROP 1 LAST PATH I61
J 2
(-8525 7500);
DISPLAY 0.978723 (-8525 7500);
PAINT WHITE (-8525 7500);
DISPLAY INVISIBLE (-8525 7500);
FORCEPROP 1 LAST PART_NUMBER CH4104K1B00
J 2
(-8525 7200);
DISPLAY 0.510638 (-8525 7200);
DISPLAY INVISIBLE (-8525 7200);
FORCEADD UNIVERSAL_GND..1
(-8150 6775);
FORCEPROP 3 LASTPIN (-8150 6825) SIG_NAME GND\g
J 0
(-8140 6835);
DISPLAY 0.659574 (-8140 6835);
PAINT MONO (-8140 6835);
DISPLAY INVISIBLE (-8140 6835);
FORCEPROP 2 LAST CDS_LIB pure_quanta_power
J 0
(-8150 6775);
PAINT MONO (-8150 6775);
DISPLAY INVISIBLE (-8150 6775);
FORCEPROP 1 LAST HDL_POWER GND
J 1
(-8125 6700);
DISPLAY 0.872340 (-8125 6700);
PAINT GREEN (-8125 6700);
DISPLAY INVISIBLE (-8125 6700);
FORCEPROP 1 LAST PATH I62
J 0
(-8075 6775);
DISPLAY 0.872340 (-8075 6775);
PAINT AQUA (-8075 6775);
DISPLAY INVISIBLE (-8075 6775);
FORCEADD UNIVERSAL_POWER..1
(-8275 7625);
FORCEPROP 3 LASTPIN (-8275 7575) SIG_NAME P3V3_AUX\g
J 0
(-8265 7585);
DISPLAY 0.659574 (-8265 7585);
PAINT MONO (-8265 7585);
DISPLAY INVISIBLE (-8265 7585);
FORCEPROP 1 LAST HDL_POWER P3V3_AUX
J 1
(-8275 7675);
DISPLAY 0.872340 (-8275 7675);
PAINT GREEN (-8275 7675);
FORCEPROP 2 LAST CDS_LIB pure_quanta_power
J 0
(-8275 7625);
PAINT MONO (-8275 7625);
DISPLAY INVISIBLE (-8275 7625);
FORCEPROP 1 LAST PATH I63
J 0
(-8225 7650);
DISPLAY 0.872340 (-8225 7650);
PAINT AQUA (-8225 7650);
DISPLAY INVISIBLE (-8225 7650);
FORCEADD 74LVC1G17GW..1
(-7975 7025);
FORCEPROP 1 LAST LOCATION U75
J 0
(-8100 7300);
DISPLAY 0.723404 (-8100 7300);
PAINT GREEN (-8100 7300);
FORCEPROP 2 LAST SEC 1
J 0
(-8075 7400);
DISPLAY 0.680851 (-8075 7400);
PAINT MONO (-8075 7400);
DISPLAY INVISIBLE (-8075 7400);
FORCEPROP 2 LASTPIN (-8150 7025) $PN 2
J 2
(-8160 7035);
DISPLAY 0.680851 (-8160 7035);
PAINT MONO (-8160 7035);
FORCEPROP 2 LASTPIN (-8150 6925) $PN 3
J 2
(-8160 6935);
DISPLAY 0.680851 (-8160 6935);
PAINT MONO (-8160 6935);
FORCEPROP 2 LASTPIN (-7800 6925) $PN 1
J 0
(-7790 6935);
DISPLAY 0.680851 (-7790 6935);
PAINT MONO (-7790 6935);
FORCEPROP 2 LASTPIN (-8150 7125) $PN 5
J 2
(-8160 7135);
DISPLAY 0.680851 (-8160 7135);
PAINT MONO (-8160 7135);
FORCEPROP 2 LASTPIN (-7800 7025) $PN 4
J 0
(-7790 7035);
DISPLAY 0.680851 (-7790 7035);
PAINT MONO (-7790 7035);
FORCEPROP 2 LAST VALUE 74LVC1G17GW
J 0
(-8100 7350);
DISPLAY 0.638298 (-8100 7350);
FORCEPROP 1 LAST MATERIAL IC
J 0
(-8109 7179);
DISPLAY 0.723404 (-8109 7179);
PAINT GREEN (-8109 7179);
FORCEPROP 2 LAST PART_TYPE SMLF
J 0
(-8100 7400);
DISPLAY 0.638298 (-8100 7400);
FORCEPROP 1 LAST PIN_NAMES_ROTATE True
J 0
(-7975 7025);
DISPLAY 0.489362 (-7975 7025);
PAINT GREEN (-7975 7025);
DISPLAY INVISIBLE (-7975 7025);
FORCEPROP 1 LAST CDS_LMAN_SYM_OUTLINE -125,150,125,-150
J 0
(-7975 7025);
DISPLAY 0.468085 (-7975 7025);
PAINT GREEN (-7975 7025);
DISPLAY INVISIBLE (-7975 7025);
FORCEPROP 2 LAST CDS_LIB pure_quanta
J 0
(-7975 7025);
DISPLAY INVISIBLE (-7975 7025);
FORCEPROP 2 LAST SEC_TYPE 
J 0
(-8075 7400);
DISPLAY 1.021277 (-8075 7400);
DISPLAY INVISIBLE (-8075 7400);
FORCEPROP 1 LAST PATH I64
J 0
(-7850 6875);
DISPLAY 0.723404 (-7850 6875);
PAINT GREEN (-7850 6875);
DISPLAY INVISIBLE (-7850 6875);
FORCEPROP 1 LAST PART_NUMBER AL1G0017K01
J 0
(-8109 7259);
DISPLAY 0.723404 (-8109 7259);
PAINT GREEN (-8109 7259);
DISPLAY INVISIBLE (-8109 7259);
FORCEADD Q_RES..1
(-8150 2525);
FORCEPROP 1 LAST LOCATION R1139
J 0
(-8400 2525);
DISPLAY 0.638298 (-8400 2525);
FORCEPROP 2 LAST $SEC 1
J 0
(-8200 2725);
DISPLAY 0.680851 (-8200 2725);
PAINT MONO (-8200 2725);
DISPLAY INVISIBLE (-8200 2725);
FORCEPROP 2 LAST CDS_SEC 1
J 0
(-8200 2725);
DISPLAY 1.021277 (-8200 2725);
DISPLAY INVISIBLE (-8200 2725);
FORCEPROP 1 LASTPIN (-8250 2525) $PN 1
J 0
(-8238 2537);
DISPLAY 0.787234 (-8238 2537);
FORCEPROP 1 LASTPIN (-8050 2525) $PN 2
J 0
(-8088 2537);
DISPLAY 0.787234 (-8088 2537);
FORCEPROP 1 LAST WATTAGE 1/16W
J 2
(-7975 2600);
DISPLAY 0.404255 (-7975 2600);
FORCEPROP 1 LAST PACK_TYPE 0402LF
J 0
(-8200 2625);
DISPLAY 0.404255 (-8200 2625);
FORCEPROP 1 LAST MATERIAL CHIP
J 0
(-8200 2600);
DISPLAY 0.404255 (-8200 2600);
FORCEPROP 1 LAST VALUE 0
J 2
(-8000 2525);
DISPLAY 0.510638 (-8000 2525);
FORCEPROP 1 LAST TOLERANCE 5%
J 0
(-7975 2525);
DISPLAY 0.510638 (-7975 2525);
FORCEPROP 2 LAST CDS_LIB pure_quanta
J 0
(-8150 2525);
PAINT MONO (-8150 2525);
DISPLAY INVISIBLE (-8150 2525);
FORCEPROP 1 LAST PATH I7
J 0
(-8200 2675);
DISPLAY 0.978723 (-8200 2675);
PAINT WHITE (-8200 2675);
DISPLAY INVISIBLE (-8200 2675);
FORCEPROP 1 LAST PART_NUMBER CS00002JB13
J 0
(-8200 2575);
DISPLAY 0.404255 (-8200 2575);
DISPLAY INVISIBLE (-8200 2575);
FORCEADD OFFPAGE..2
(-6200 6875);
FORCEPROP 2 LAST $XR0 131 
J 0
(-6011 6875);
DISPLAY 0.638298 (-6011 6875);
PAINT MONO (-6011 6875);
FORCEPROP 2 LAST CDS_LIB standard
J 0
(-6200 6875);
DISPLAY INVISIBLE (-6200 6875);
FORCEPROP 1 LAST OFFPAGE TRUE
J 0
(-5875 6750);
DISPLAY 0.872340 (-5875 6750);
PAINT GREEN (-5875 6750);
DISPLAY INVISIBLE (-5875 6750);
FORCEPROP 1 LAST COMMENT_BODY TRUE
J 0
(-6245 6780);
DISPLAY 0.872340 (-6245 6780);
PAINT GREEN (-6245 6780);
DISPLAY INVISIBLE (-6245 6780);
FORCEPROP 2 LAST PATH I74
J 0
(-6000 6925);
DISPLAY 0.680851 (-6000 6925);
DISPLAY INVISIBLE (-6000 6925);
FORCEADD OFFPAGE..2
(-6200 7025);
FORCEPROP 2 LAST $XR0 131 
J 0
(-6011 7025);
DISPLAY 0.638298 (-6011 7025);
PAINT MONO (-6011 7025);
FORCEPROP 2 LAST CDS_LIB standard
J 0
(-6200 7025);
DISPLAY INVISIBLE (-6200 7025);
FORCEPROP 1 LAST OFFPAGE TRUE
J 0
(-5875 6900);
DISPLAY 0.872340 (-5875 6900);
PAINT GREEN (-5875 6900);
DISPLAY INVISIBLE (-5875 6900);
FORCEPROP 1 LAST COMMENT_BODY TRUE
J 0
(-6245 6930);
DISPLAY 0.872340 (-6245 6930);
PAINT GREEN (-6245 6930);
DISPLAY INVISIBLE (-6245 6930);
FORCEPROP 2 LAST PATH I75
J 0
(-6000 7075);
DISPLAY 0.680851 (-6000 7075);
DISPLAY INVISIBLE (-6000 7075);
FORCEADD OFFPAGE..2
(-6200 6975);
FORCEPROP 2 LAST $XR0 131 
J 0
(-6011 6975);
DISPLAY 0.638298 (-6011 6975);
PAINT MONO (-6011 6975);
FORCEPROP 2 LAST CDS_LIB standard
J 0
(-6200 6975);
DISPLAY INVISIBLE (-6200 6975);
FORCEPROP 1 LAST OFFPAGE TRUE
J 0
(-5875 6850);
DISPLAY 0.872340 (-5875 6850);
PAINT GREEN (-5875 6850);
DISPLAY INVISIBLE (-5875 6850);
FORCEPROP 1 LAST COMMENT_BODY TRUE
J 0
(-6245 6880);
DISPLAY 0.872340 (-6245 6880);
PAINT GREEN (-6245 6880);
DISPLAY INVISIBLE (-6245 6880);
FORCEPROP 2 LAST PATH I76
J 0
(-6000 7025);
DISPLAY 0.680851 (-6000 7025);
DISPLAY INVISIBLE (-6000 7025);
FORCEADD OFFPAGE..2
(-6200 6925);
FORCEPROP 2 LAST $XR0 131 
J 0
(-6011 6925);
DISPLAY 0.638298 (-6011 6925);
PAINT MONO (-6011 6925);
FORCEPROP 2 LAST CDS_LIB standard
J 0
(-6200 6925);
DISPLAY INVISIBLE (-6200 6925);
FORCEPROP 1 LAST OFFPAGE TRUE
J 0
(-5875 6800);
DISPLAY 0.872340 (-5875 6800);
PAINT GREEN (-5875 6800);
DISPLAY INVISIBLE (-5875 6800);
FORCEPROP 1 LAST COMMENT_BODY TRUE
J 0
(-6245 6830);
DISPLAY 0.872340 (-6245 6830);
PAINT GREEN (-6245 6830);
DISPLAY INVISIBLE (-6245 6830);
FORCEPROP 2 LAST PATH I77
J 0
(-6000 6975);
DISPLAY 0.680851 (-6000 6975);
DISPLAY INVISIBLE (-6000 6975);
FORCEADD Q_RES..1
(-6975 6975);
FORCEPROP 1 LAST LOCATION R899
J 0
(-6875 6975);
DISPLAY 0.489362 (-6875 6975);
PAINT SKYBLUE (-6875 6975);
FORCEPROP 0 LAST $SEC 1
J 0
(-6875 7025);
DISPLAY 0.680851 (-6875 7025);
PAINT MONO (-6875 7025);
DISPLAY INVISIBLE (-6875 7025);
FORCEPROP 0 LAST CDS_SEC 1
J 0
(-6875 7025);
DISPLAY 0.680851 (-6875 7025);
DISPLAY INVISIBLE (-6875 7025);
FORCEPROP 1 LASTPIN (-7075 6975) $PN 1
J 0
(-7063 6987);
DISPLAY 0.489362 (-7063 6987);
PAINT MONO (-7063 6987);
FORCEPROP 1 LASTPIN (-6875 6975) $PN 2
J 0
(-6913 6987);
DISPLAY 0.489362 (-6913 6987);
PAINT MONO (-6913 6987);
FORCEPROP 1 LAST VALUE 0
J 2
(-7100 6975);
DISPLAY 0.489362 (-7100 6975);
PAINT SKYBLUE (-7100 6975);
FORCEPROP 2 LAST CDS_LIB pure_quanta
J 0
(-6975 6975);
DISPLAY INVISIBLE (-6975 6975);
FORCEPROP 2 LAST BOM_COST MEM
J 2
(-6950 7125);
DISPLAY 0.744681 (-6950 7125);
PAINT WHITE (-6950 7125);
DISPLAY INVISIBLE (-6950 7125);
FORCEPROP 1 LAST WATTAGE 1/16W
J 2
(-7050 6900);
DISPLAY 0.489362 (-7050 6900);
PAINT SKYBLUE (-7050 6900);
DISPLAY INVISIBLE (-7050 6900);
FORCEPROP 1 LAST MATERIAL CHIP
J 2
(-6800 6950);
DISPLAY 0.489362 (-6800 6950);
PAINT SKYBLUE (-6800 6950);
DISPLAY INVISIBLE (-6800 6950);
FORCEPROP 1 LAST TOLERANCE 5%
J 0
(-7100 6950);
DISPLAY 0.489362 (-7100 6950);
PAINT SKYBLUE (-7100 6950);
DISPLAY INVISIBLE (-7100 6950);
FORCEPROP 1 LAST PACK_TYPE 0402LF
J 2
(-6800 6900);
DISPLAY 0.489362 (-6800 6900);
PAINT SKYBLUE (-6800 6900);
DISPLAY INVISIBLE (-6800 6900);
FORCEPROP 1 LAST PATH I78
J 0
(-7025 7125);
DISPLAY 0.978723 (-7025 7125);
PAINT WHITE (-7025 7125);
DISPLAY INVISIBLE (-7025 7125);
FORCEPROP 1 LAST PART_NUMBER CS00002JB13
J 2
(-6875 7025);
DISPLAY 0.489362 (-6875 7025);
PAINT SKYBLUE (-6875 7025);
DISPLAY INVISIBLE (-6875 7025);
FORCEADD Q_RES..1
(-6975 7025);
FORCEPROP 1 LAST LOCATION R877
J 0
(-6875 7025);
DISPLAY 0.489362 (-6875 7025);
PAINT SKYBLUE (-6875 7025);
FORCEPROP 0 LAST $SEC 1
J 0
(-6875 7075);
DISPLAY 0.680851 (-6875 7075);
PAINT MONO (-6875 7075);
DISPLAY INVISIBLE (-6875 7075);
FORCEPROP 0 LAST CDS_SEC 1
J 0
(-6875 7075);
DISPLAY 0.680851 (-6875 7075);
DISPLAY INVISIBLE (-6875 7075);
FORCEPROP 1 LASTPIN (-7075 7025) $PN 1
J 0
(-7063 7037);
DISPLAY 0.489362 (-7063 7037);
PAINT MONO (-7063 7037);
FORCEPROP 1 LASTPIN (-6875 7025) $PN 2
J 0
(-6913 7037);
DISPLAY 0.489362 (-6913 7037);
PAINT MONO (-6913 7037);
FORCEPROP 1 LAST VALUE 0
J 2
(-7100 7025);
DISPLAY 0.489362 (-7100 7025);
PAINT SKYBLUE (-7100 7025);
FORCEPROP 1 LAST PACK_TYPE 0402LF
J 2
(-6800 6950);
DISPLAY 0.489362 (-6800 6950);
PAINT SKYBLUE (-6800 6950);
DISPLAY INVISIBLE (-6800 6950);
FORCEPROP 1 LAST TOLERANCE 5%
J 0
(-7100 7000);
DISPLAY 0.489362 (-7100 7000);
PAINT SKYBLUE (-7100 7000);
DISPLAY INVISIBLE (-7100 7000);
FORCEPROP 1 LAST MATERIAL CHIP
J 2
(-6800 7000);
DISPLAY 0.489362 (-6800 7000);
PAINT SKYBLUE (-6800 7000);
DISPLAY INVISIBLE (-6800 7000);
FORCEPROP 1 LAST WATTAGE 1/16W
J 2
(-7050 6950);
DISPLAY 0.489362 (-7050 6950);
PAINT SKYBLUE (-7050 6950);
DISPLAY INVISIBLE (-7050 6950);
FORCEPROP 2 LAST BOM_COST MEM
J 2
(-6950 7175);
DISPLAY 0.744681 (-6950 7175);
PAINT WHITE (-6950 7175);
DISPLAY INVISIBLE (-6950 7175);
FORCEPROP 2 LAST CDS_LIB pure_quanta
J 0
(-6975 7025);
DISPLAY INVISIBLE (-6975 7025);
FORCEPROP 1 LAST PATH I79
J 0
(-7025 7175);
DISPLAY 0.978723 (-7025 7175);
PAINT WHITE (-7025 7175);
DISPLAY INVISIBLE (-7025 7175);
FORCEPROP 1 LAST PART_NUMBER CS00002JB13
J 2
(-6875 7075);
DISPLAY 0.489362 (-6875 7075);
PAINT SKYBLUE (-6875 7075);
DISPLAY INVISIBLE (-6875 7075);
FORCEADD 74LVC1G126SE7..1
(-8175 4250);
FORCEPROP 1 LAST LOCATION U8082
J 0
(-8069 4081);
DISPLAY 0.723404 (-8069 4081);
PAINT GREEN (-8069 4081);
FORCEPROP 0 LAST $SEC 1
J 0
(-8050 4475);
DISPLAY 0.680851 (-8050 4475);
PAINT MONO (-8050 4475);
DISPLAY INVISIBLE (-8050 4475);
FORCEPROP 0 LAST CDS_SEC 1
J 0
(-8050 4475);
DISPLAY 1.021277 (-8050 4475);
DISPLAY INVISIBLE (-8050 4475);
FORCEPROP 0 LASTPIN (-8425 4300) $PN 2
J 2
(-8435 4310);
DISPLAY 0.680851 (-8435 4310);
PAINT MONO (-8435 4310);
FORCEPROP 0 LASTPIN (-8175 4000) $PN 3
R 1
J 2
(-8185 3990);
DISPLAY 0.680851 (-8185 3990);
PAINT MONO (-8185 3990);
FORCEPROP 0 LASTPIN (-8425 4200) $PN 1
J 2
(-8435 4210);
DISPLAY 0.680851 (-8435 4210);
PAINT MONO (-8435 4210);
FORCEPROP 0 LASTPIN (-8175 4500) $PN 5
R 1
J 0
(-8185 4510);
DISPLAY 0.680851 (-8185 4510);
PAINT MONO (-8185 4510);
FORCEPROP 0 LASTPIN (-7925 4250) $PN 4
J 0
(-7915 4260);
DISPLAY 0.680851 (-7915 4260);
PAINT MONO (-7915 4260);
FORCEPROP 2 LAST VALUE 74LVC1G126SE-7
J 0
(-8150 4400);
DISPLAY 0.638298 (-8150 4400);
FORCEPROP 2 LAST PART_TYPE SMLF
J 0
(-8050 4425);
DISPLAY 0.638298 (-8050 4425);
FORCEPROP 1 LAST MATERIAL IC
J 0
(-8069 3807);
DISPLAY 0.723404 (-8069 3807);
PAINT GREEN (-8069 3807);
FORCEPROP 1 LAST NEEDS_NO_SIZE TRUE
J 0
(-8175 4250);
DISPLAY 0.723404 (-8175 4250);
PAINT GREEN (-8175 4250);
DISPLAY INVISIBLE (-8175 4250);
FORCEPROP 1 LAST CDS_LMAN_SYM_OUTLINE -100,100,100,-100
J 0
(-8175 4250);
DISPLAY 0.468085 (-8175 4250);
PAINT GREEN (-8175 4250);
DISPLAY INVISIBLE (-8175 4250);
FORCEPROP 2 LAST CDS_LIB pure_quanta
J 0
(-8175 4250);
DISPLAY INVISIBLE (-8175 4250);
FORCEPROP 1 LAST PATH I8
J 0
(-8175 4250);
DISPLAY 0.723404 (-8175 4250);
PAINT GREEN (-8175 4250);
DISPLAY INVISIBLE (-8175 4250);
FORCEPROP 1 LAST PART_NUMBER AL1G0126009
J 0
(-8094 3959);
DISPLAY 0.723404 (-8094 3959);
PAINT GREEN (-8094 3959);
DISPLAY INVISIBLE (-8094 3959);
FORCEADD Q_RES..1
(-6975 6925);
FORCEPROP 1 LAST LOCATION R905
J 0
(-6875 6925);
DISPLAY 0.489362 (-6875 6925);
PAINT SKYBLUE (-6875 6925);
FORCEPROP 0 LAST $SEC 1
J 0
(-6875 6975);
DISPLAY 0.680851 (-6875 6975);
PAINT MONO (-6875 6975);
DISPLAY INVISIBLE (-6875 6975);
FORCEPROP 0 LAST CDS_SEC 1
J 0
(-6875 6975);
DISPLAY 0.680851 (-6875 6975);
DISPLAY INVISIBLE (-6875 6975);
FORCEPROP 1 LASTPIN (-7075 6925) $PN 1
J 0
(-7063 6937);
DISPLAY 0.489362 (-7063 6937);
PAINT MONO (-7063 6937);
FORCEPROP 1 LASTPIN (-6875 6925) $PN 2
J 0
(-6913 6937);
DISPLAY 0.489362 (-6913 6937);
PAINT MONO (-6913 6937);
FORCEPROP 1 LAST VALUE 0
J 2
(-7100 6925);
DISPLAY 0.489362 (-7100 6925);
PAINT SKYBLUE (-7100 6925);
FORCEPROP 2 LAST CDS_LIB pure_quanta
J 0
(-6975 6925);
DISPLAY INVISIBLE (-6975 6925);
FORCEPROP 2 LAST BOM_COST MEM
J 2
(-6950 7075);
DISPLAY 0.744681 (-6950 7075);
PAINT WHITE (-6950 7075);
DISPLAY INVISIBLE (-6950 7075);
FORCEPROP 1 LAST WATTAGE 1/16W
J 2
(-7050 6850);
DISPLAY 0.489362 (-7050 6850);
PAINT SKYBLUE (-7050 6850);
DISPLAY INVISIBLE (-7050 6850);
FORCEPROP 1 LAST MATERIAL CHIP
J 2
(-6800 6900);
DISPLAY 0.489362 (-6800 6900);
PAINT SKYBLUE (-6800 6900);
DISPLAY INVISIBLE (-6800 6900);
FORCEPROP 1 LAST TOLERANCE 5%
J 0
(-7100 6900);
DISPLAY 0.489362 (-7100 6900);
PAINT SKYBLUE (-7100 6900);
DISPLAY INVISIBLE (-7100 6900);
FORCEPROP 1 LAST PACK_TYPE 0402LF
J 2
(-6800 6850);
DISPLAY 0.489362 (-6800 6850);
PAINT SKYBLUE (-6800 6850);
DISPLAY INVISIBLE (-6800 6850);
FORCEPROP 1 LAST PATH I80
J 0
(-7025 7075);
DISPLAY 0.978723 (-7025 7075);
PAINT WHITE (-7025 7075);
DISPLAY INVISIBLE (-7025 7075);
FORCEPROP 1 LAST PART_NUMBER CS00002JB13
J 2
(-6875 6975);
DISPLAY 0.489362 (-6875 6975);
PAINT SKYBLUE (-6875 6975);
DISPLAY INVISIBLE (-6875 6975);
FORCEADD Q_RES..1
(-6975 6875);
FORCEPROP 1 LAST LOCATION R956
J 0
(-6875 6875);
DISPLAY 0.489362 (-6875 6875);
PAINT SKYBLUE (-6875 6875);
FORCEPROP 0 LAST $SEC 1
J 0
(-6875 6925);
DISPLAY 0.680851 (-6875 6925);
PAINT MONO (-6875 6925);
DISPLAY INVISIBLE (-6875 6925);
FORCEPROP 0 LAST CDS_SEC 1
J 0
(-6875 6925);
DISPLAY 0.680851 (-6875 6925);
DISPLAY INVISIBLE (-6875 6925);
FORCEPROP 1 LASTPIN (-7075 6875) $PN 1
J 0
(-7063 6887);
DISPLAY 0.489362 (-7063 6887);
PAINT MONO (-7063 6887);
FORCEPROP 1 LASTPIN (-6875 6875) $PN 2
J 0
(-6913 6887);
DISPLAY 0.489362 (-6913 6887);
PAINT MONO (-6913 6887);
FORCEPROP 1 LAST VALUE 0
J 2
(-7100 6875);
DISPLAY 0.489362 (-7100 6875);
PAINT SKYBLUE (-7100 6875);
FORCEPROP 2 LAST CDS_LIB pure_quanta
J 0
(-6975 6875);
DISPLAY INVISIBLE (-6975 6875);
FORCEPROP 2 LAST BOM_COST MEM
J 2
(-6950 7025);
DISPLAY 0.744681 (-6950 7025);
PAINT WHITE (-6950 7025);
DISPLAY INVISIBLE (-6950 7025);
FORCEPROP 1 LAST WATTAGE 1/16W
J 2
(-7050 6800);
DISPLAY 0.489362 (-7050 6800);
PAINT SKYBLUE (-7050 6800);
DISPLAY INVISIBLE (-7050 6800);
FORCEPROP 1 LAST MATERIAL CHIP
J 2
(-6800 6850);
DISPLAY 0.489362 (-6800 6850);
PAINT SKYBLUE (-6800 6850);
DISPLAY INVISIBLE (-6800 6850);
FORCEPROP 1 LAST TOLERANCE 5%
J 0
(-7100 6850);
DISPLAY 0.489362 (-7100 6850);
PAINT SKYBLUE (-7100 6850);
DISPLAY INVISIBLE (-7100 6850);
FORCEPROP 1 LAST PACK_TYPE 0402LF
J 2
(-6800 6800);
DISPLAY 0.489362 (-6800 6800);
PAINT SKYBLUE (-6800 6800);
DISPLAY INVISIBLE (-6800 6800);
FORCEPROP 1 LAST PATH I81
J 0
(-7025 7025);
DISPLAY 0.978723 (-7025 7025);
PAINT WHITE (-7025 7025);
DISPLAY INVISIBLE (-7025 7025);
FORCEPROP 1 LAST PART_NUMBER CS00002JB13
J 2
(-6875 6925);
DISPLAY 0.489362 (-6875 6925);
PAINT SKYBLUE (-6875 6925);
DISPLAY INVISIBLE (-6875 6925);
FORCEADD 74LVC1G66GV..1
(-3175 3275);
FORCEPROP 1 LAST LOCATION U320
J 0
(-3330 3615);
DISPLAY 0.723404 (-3330 3615);
PAINT GREEN (-3330 3615);
FORCEPROP 2 LAST SEC 1
J 0
(-3325 3750);
DISPLAY 0.680851 (-3325 3750);
PAINT MONO (-3325 3750);
DISPLAY INVISIBLE (-3325 3750);
FORCEPROP 2 LASTPIN (-2875 3225) $PN 4
J 0
(-2865 3235);
DISPLAY 0.680851 (-2865 3235);
PAINT MONO (-2865 3235);
FORCEPROP 2 LASTPIN (-3475 3175) $PN 3
J 2
(-3485 3185);
DISPLAY 0.680851 (-3485 3185);
PAINT MONO (-3485 3185);
FORCEPROP 2 LASTPIN (-2875 3375) $PN 5
J 0
(-2865 3385);
DISPLAY 0.680851 (-2865 3385);
PAINT MONO (-2865 3385);
FORCEPROP 2 LASTPIN (-3475 3375) $PN 1
J 2
(-3485 3385);
DISPLAY 0.680851 (-3485 3385);
PAINT MONO (-3485 3385);
FORCEPROP 2 LASTPIN (-3475 3275) $PN 2
J 2
(-3485 3285);
DISPLAY 0.680851 (-3485 3285);
PAINT MONO (-3485 3285);
FORCEPROP 2 LAST VALUE 74LVC1G66GV
J 0
(-3325 3650);
DISPLAY 0.680851 (-3325 3650);
FORCEPROP 2 LAST PART_TYPE SMLF
J 0
(-3325 3700);
DISPLAY 0.680851 (-3325 3700);
FORCEPROP 1 LAST MATERIAL IC
J 0
(-3330 3430);
DISPLAY 0.723404 (-3330 3430);
PAINT GREEN (-3330 3430);
FORCEPROP 2 LAST SEC_TYPE 
J 0
(-3325 3750);
DISPLAY 0.680851 (-3325 3750);
DISPLAY INVISIBLE (-3325 3750);
FORCEPROP 2 LAST CDS_LIB pure_quanta
J 0
(-3175 3275);
DISPLAY INVISIBLE (-3175 3275);
FORCEPROP 1 LAST PIN_NAMES_ROTATE True
J 0
(-3175 3275);
DISPLAY 0.489362 (-3175 3275);
PAINT GREEN (-3175 3275);
DISPLAY INVISIBLE (-3175 3275);
FORCEPROP 1 LAST CDS_LMAN_SYM_OUTLINE -150,150,150,-150
J 0
(-3175 3275);
DISPLAY 0.468085 (-3175 3275);
PAINT GREEN (-3175 3275);
DISPLAY INVISIBLE (-3175 3275);
FORCEPROP 1 LAST PATH I82
J 0
(-3025 3125);
DISPLAY 0.723404 (-3025 3125);
PAINT GREEN (-3025 3125);
DISPLAY INVISIBLE (-3025 3125);
FORCEPROP 1 LAST PART_NUMBER AL001G66000
J 0
(-3330 3519);
DISPLAY 0.723404 (-3330 3519);
PAINT GREEN (-3330 3519);
DISPLAY INVISIBLE (-3330 3519);
FORCEADD UNIVERSAL_GND..1
(-8175 3800);
FORCEPROP 3 LASTPIN (-8175 3850) SIG_NAME GND\g
J 0
(-8165 3860);
DISPLAY 0.659574 (-8165 3860);
PAINT MONO (-8165 3860);
DISPLAY INVISIBLE (-8165 3860);
FORCEPROP 2 LAST CDS_LIB pure_quanta_power
J 0
(-8175 3800);
PAINT MONO (-8175 3800);
DISPLAY INVISIBLE (-8175 3800);
FORCEPROP 1 LAST HDL_POWER GND
J 1
(-8150 3725);
DISPLAY 0.872340 (-8150 3725);
PAINT GREEN (-8150 3725);
DISPLAY INVISIBLE (-8150 3725);
FORCEPROP 1 LAST PATH I9
J 0
(-8100 3800);
DISPLAY 0.872340 (-8100 3800);
PAINT AQUA (-8100 3800);
DISPLAY INVISIBLE (-8100 3800);
FORCEADD DNS..2
(-3775 4575);
PAINT RED (-3775 4575);
FORCEPROP 2 LAST CDS_LIB mstr_misc
J 0
(-3775 4575);
DISPLAY INVISIBLE (-3775 4575);
FORCEPROP 1 LAST COMMENT_BODY TRUE
R 1
J 0
(-3700 4350);
DISPLAY 0.872340 (-3700 4350);
PAINT GREEN (-3700 4350);
DISPLAY INVISIBLE (-3700 4350);
FORCEADD CAD_NOTE..1
(-3125 4825);
FORCEPROP 0 LAST S1 PLACE R2487 CLOSE TO U157
J 0
(-3275 4675);
DISPLAY 0.808511 (-3275 4675);
PAINT SKYBLUE (-3275 4675);
FORCEPROP 2 LAST CDS_LIB pure_quanta_power
J 0
(-3125 4825);
DISPLAY INVISIBLE (-3125 4825);
FORCEPROP 1 LAST COMMENT_BODY TRUE
J 0
(-3100 4925);
DISPLAY 0.978723 (-3100 4925);
DISPLAY INVISIBLE (-3100 4925);
FORCEADD QUANTA_TITLE_BLOCK_C..1
(-1575 1525);
FORCEPROP 0 LAST CDS_CON_LAST_MODIFIED Thu Sep 14 16:12:25 2023
J 0
(-3460 1540);
PAINT MONO (-3460 1540);
DISPLAY INVISIBLE (-3460 1540);
FORCEPROP 1 LAST CUSTOM_TXT_CDS <CON_LAST_MODIFIED>
J 0
(-3460 1540);
DISPLAY 0.978723 (-3460 1540);
FORCEPROP 2 LAST CUSTOM_TXT_CDS <XR_PAGE_TITLE>
J 0
(-9465 6775);
DISPLAY 0.638298 (-9465 6775);
PAINT PINK (-9465 6775);
DISPLAY INVISIBLE (-9465 6775);
FORCEPROP 2 LAST CUSTOM_TXT_CDS <Q_NUMBER>
J 0
(-2978 1628);
DISPLAY 1.212766 (-2978 1628);
FORCEPROP 2 LAST CUSTOM_TXT_CDS <CON_PAGE_NUM> OF <CON_TOTAL_PAGES>
J 0
(-2046 1543);
DISPLAY 0.978723 (-2046 1543);
FORCEPROP 1 LAST CUSTOM_TXT_CDS <NAME_2>
J 0
(-4750 1575);
FORCEPROP 1 LAST CUSTOM_TXT_CDS <NAME_1>
J 0
(-4750 1700);
FORCEPROP 1 LAST CUSTOM_TXT_CDS <Q_PROJ>
J 0
(-3957 1627);
DISPLAY 1.212766 (-3957 1627);
FORCEPROP 1 LAST CUSTOM_TXT_CDS <Q_REV>
J 0
(-1759 1628);
DISPLAY 1.212766 (-1759 1628);
FORCEPROP 1 LAST Q_TITLE PCIE - SFF OCP3.0 (3/3)
J 0
(-10941 1551);
DISPLAY 1.957447 (-10941 1551);
PAINT GREEN (-10941 1551);
FORCEPROP 2 LAST CDS_LIB pure_quanta
J 0
(-1575 1525);
PAINT MONO (-1575 1525);
DISPLAY INVISIBLE (-1575 1525);
FORCEPROP 1 LAST CDS_LMAN_SYM_OUTLINE -9475,6775,100,-125
J 0
(-1575 1525);
DISPLAY 0.468085 (-1575 1525);
PAINT GREEN (-1575 1525);
DISPLAY INVISIBLE (-1575 1525);
FORCEPROP 2 LAST PAGE_BORDER TRUE
J 0
(-9465 6775);
DISPLAY 0.638298 (-9465 6775);
PAINT PINK (-9465 6775);
DISPLAY INVISIBLE (-9465 6775);
FORCEPROP 2 LAST CDS_XR_PAGE_TITLE CR-133 : @T6G_MB_LIB.T6G(SCH_1):PAGE133
J 0
(-9465 6775);
DISPLAY 0.638298 (-9465 6775);
PAINT PINK (-9465 6775);
DISPLAY INVISIBLE (-9465 6775);
FORCEPROP 1 LAST Q_DEPT BU9
J 1
(-5338 1574);
DISPLAY 1.957447 (-5338 1574);
PAINT GREEN (-5338 1574);
DISPLAY INVISIBLE (-5338 1574);
FORCEPROP 1 LAST COMMENT_BODY TRUE
J 0
(-1563 1512);
DISPLAY 0.978723 (-1563 1512);
PAINT GREEN (-1563 1512);
DISPLAY INVISIBLE (-1563 1512);
WIRE 16 -1 (-6250 2750)(-6250 2675);
WIRE 16 -1 (-9875 2575)(-9875 2650);
WIRE 16 -1 (-5225 4150)(-5425 4150);
WIRE 16 -1 (-5425 4150)(-5425 3975);
WIRE 16 -1 (-7900 4700)(-7900 4625);
WIRE 16 -1 (-7050 4800)(-7050 4850);
WIRE 16 -1 (-7525 5725)(-7725 5725);
WIRE 16 -1 (-7725 5725)(-7725 5550);
WIRE 16 -1 (-6575 6100)(-6575 6025);
WIRE 16 -1 (-5875 6200)(-5875 6250);
WIRE 16 -1 (-4325 4425)(-4325 4350);
WIRE 16 -1 (-3475 3175)(-3600 3175);
WIRE 16 -1 (-3600 3175)(-3600 3075);
WIRE 16 -1 (-2525 3450)(-2525 3375);
WIRE 16 -1 (-3775 4700)(-3775 4750);
WIRE 16 -1 (-8475 7250)(-8475 7175);
WIRE 16 -1 (-8150 6925)(-8150 6825);
WIRE 16 -1 (-8175 4000)(-8175 3850);
WIRE 16 -1 (-4725 3275)(-5650 3275);
FORCEPROP 0 LAST CDS_PHYS_NET_NAME CLK_50M_NCSI_OCP_SFF_ISO
J 0
(-5285 3309);
PAINT MONO (-5285 3309);
DISPLAY INVISIBLE (-5285 3309);
FORCEPROP 2 LAST SIG_NAME CLK_50M_NCSI_OCP_SFF_ISO
J 0
(-5535 3285);
DISPLAY 0.510638 (-5535 3285);
PAINT WHITE (-5535 3285);
WIRE 16 -1 (-3475 3275)(-4525 3275);
FORCEPROP 0 LAST CDS_PHYS_NET_NAME CLK_50M_NCSI_OCP_SFF_ISO_R
J 0
(-4160 3309);
PAINT MONO (-4160 3309);
DISPLAY INVISIBLE (-4160 3309);
FORCEPROP 2 LAST SIG_NAME CLK_50M_NCSI_OCP_SFF_ISO_R
J 0
(-4285 3285);
DISPLAY 0.510638 (-4285 3285);
PAINT WHITE (-4285 3285);
FORCEPROP 2 LASTPROP $XRERR UNIQUE?
J 0
(-4525 3285);
DISPLAY 0.638298 (-4525 3285);
PAINT MONO (-4525 3285);
DISPLAY INVISIBLE (-4525 3285);
WIRE 16 -1 (-4400 2525)(-5450 2525);
FORCEPROP 0 LAST CDS_PHYS_NET_NAME CLK_50M_RMII_BMC_OCP
J 0
(-5085 2559);
PAINT MONO (-5085 2559);
DISPLAY INVISIBLE (-5085 2559);
FORCEPROP 2 LAST SIG_NAME CLK_50M_RMII_BMC_OCP
J 0
(-4960 2535);
DISPLAY 0.510638 (-4960 2535);
PAINT WHITE (-4960 2535);
WIRE 16 -1 (-3775 4500)(-3775 4150);
WIRE 16 -1 (-3775 4150)(-3575 4150);
WIRE 16 -1 (-4675 4150)(-3775 4150);
FORCEPROP 0 LAST CDS_PHYS_NET_NAME IRQ_LVC3_WAKE_BUF_N
J 0
(-4650 4192);
PAINT MONO (-4650 4192);
DISPLAY INVISIBLE (-4650 4192);
FORCEPROP 0 LAST SIG_NAME IRQ_LVC3_WAKE_BUF_N
J 0
(-4510 4160);
DISPLAY 0.702128 (-4510 4160);
PAINT WHITE (-4510 4160);
FORCEPROP 2 LASTPROP $XRERR UNIQUE?
J 0
(-4750 4160);
DISPLAY 0.638298 (-4750 4160);
PAINT MONO (-4750 4160);
DISPLAY INVISIBLE (-4750 4160);
WIRE 16 -1 (-7250 6875)(-7075 6875);
WIRE 16 -1 (-7250 6925)(-7250 6875);
WIRE 16 -1 (-7250 6925)(-7075 6925);
WIRE 16 -1 (-7250 6975)(-7250 6925);
WIRE 16 -1 (-7250 6975)(-7075 6975);
WIRE 16 -1 (-7250 7025)(-7250 6975);
WIRE 16 -1 (-7250 7025)(-7075 7025);
WIRE 16 -1 (-7800 7025)(-7250 7025);
FORCEPROP 2 LAST SIG_NAME RST_PERST_OCP_SFF_BUF2_N
J 0
(-7735 7035);
DISPLAY 0.446809 (-7735 7035);
PAINT SKYBLUE (-7735 7035);
FORCEPROP 2 LASTPROP $XRERR UNIQUE?
J 0
(-7975 7035);
DISPLAY 0.638298 (-7975 7035);
PAINT MONO (-7975 7035);
DISPLAY INVISIBLE (-7975 7035);
WIRE 16 -1 (-9400 4200)(-8425 4200);
FORCEPROP 0 LAST CDS_PHYS_NET_NAME PU_OCP_SFF_WAKE_OE
J 0
(-9160 4242);
PAINT MONO (-9160 4242);
DISPLAY INVISIBLE (-9160 4242);
FORCEPROP 2 LAST SIG_NAME PU_OCP_SFF_WAKE_OE
J 0
(-9285 4210);
DISPLAY 0.680851 (-9285 4210);
PAINT WHITE (-9285 4210);
FORCEPROP 2 LASTPROP $XRERR UNIQUE?
J 0
(-9525 4210);
DISPLAY 0.638298 (-9525 4210);
PAINT MONO (-9525 4210);
DISPLAY INVISIBLE (-9525 4210);
WIRE 16 -1 (-9400 4525)(-9400 4200);
WIRE 16 -1 (-8475 7525)(-8275 7525);
WIRE 16 -1 (-8475 7525)(-8475 7450);
WIRE 16 -1 (-8275 7125)(-8275 7525);
WIRE 16 -1 (-8275 7525)(-8275 7575);
WIRE 16 -1 (-8150 7125)(-8275 7125);
WIRE 16 -1 (-9075 7025)(-8150 7025);
FORCEPROP 0 LAST CDS_PHYS_NET_NAME RST_HP_OCP_V3_1_N
J 0
(-8710 7067);
PAINT MONO (-8710 7067);
DISPLAY INVISIBLE (-8710 7067);
FORCEPROP 2 LAST SIG_NAME RST_PERST_OCP_SFF_BUF_N
J 0
(-9010 7060);
DISPLAY 0.680851 (-9010 7060);
PAINT SKYBLUE (-9010 7060);
WIRE 16 -1 (-6875 7025)(-6250 7025);
FORCEPROP 2 LAST SIG_NAME RST_PERST0_OCP_SFF_N
J 0
(-6710 7035);
DISPLAY 0.489362 (-6710 7035);
PAINT SKYBLUE (-6710 7035);
WIRE 16 -1 (-6875 6975)(-6250 6975);
FORCEPROP 2 LAST SIG_NAME RST_PERST1_OCP_SFF_N
J 0
(-6710 6985);
DISPLAY 0.489362 (-6710 6985);
PAINT SKYBLUE (-6710 6985);
WIRE 16 -1 (-6875 6925)(-6250 6925);
FORCEPROP 2 LAST SIG_NAME RST_PERST2_OCP_SFF_N
J 0
(-6710 6935);
DISPLAY 0.489362 (-6710 6935);
PAINT SKYBLUE (-6710 6935);
WIRE 16 -1 (-6875 6875)(-6250 6875);
FORCEPROP 2 LAST SIG_NAME RST_PERST3_OCP_SFF_N
J 0
(-6710 6885);
DISPLAY 0.489362 (-6710 6885);
PAINT SKYBLUE (-6710 6885);
WIRE 16 -1 (-4400 2425)(-5450 2425);
FORCEPROP 0 LAST CDS_PHYS_NET_NAME CLK_50M_NCSI_OCP_V3_2
J 0
(-5085 2459);
PAINT MONO (-5085 2459);
DISPLAY INVISIBLE (-5085 2459);
FORCEPROP 2 LAST SIG_NAME CLK_50M_NCSI_OCP_V3_2
J 0
(-4960 2435);
DISPLAY 0.510638 (-4960 2435);
PAINT WHITE (-4960 2435);
WIRE 16 -1 (-5225 4350)(-5900 4350);
FORCEPROP 0 LAST CDS_PHYS_NET_NAME NC_U157_NC1
J 0
(-5875 4392);
PAINT MONO (-5875 4392);
DISPLAY INVISIBLE (-5875 4392);
FORCEPROP 0 LAST SIG_NAME NC_U157_NC1
J 0
(-5785 4360);
DISPLAY 0.702128 (-5785 4360);
PAINT WHITE (-5785 4360);
FORCEPROP 2 LASTPROP $XRERR UNIQUE?
J 0
(-6140 4350);
DISPLAY 0.638298 (-6140 4350);
PAINT MONO (-6140 4350);
DISPLAY INVISIBLE (-6140 4350);
WIRE 16 -1 (-6975 5925)(-6775 5925);
WIRE 16 -1 (-6775 6375)(-6775 5925);
WIRE 16 -1 (-6775 6375)(-6575 6375);
WIRE 16 -1 (-6775 6425)(-6775 6375);
WIRE 16 -1 (-6575 6375)(-6575 6300);
WIRE 16 -1 (-5425 5725)(-5875 5725);
WIRE 16 -1 (-5875 6000)(-5875 5725);
WIRE 16 -1 (-5875 5725)(-6975 5725);
FORCEPROP 0 LAST CDS_PHYS_NET_NAME OCP_SFF_PWRBRK_BUFF_N
J 0
(-6460 5767);
PAINT MONO (-6460 5767);
DISPLAY INVISIBLE (-6460 5767);
FORCEPROP 2 LAST SIG_NAME OCP_SFF_PWRBRK_BUFF_N
J 0
(-6710 5735);
DISPLAY 0.680851 (-6710 5735);
PAINT WHITE (-6710 5735);
FORCEPROP 2 LASTPROP $XRERR UNIQUE?
J 0
(-6950 5735);
DISPLAY 0.638298 (-6950 5735);
PAINT MONO (-6950 5735);
DISPLAY INVISIBLE (-6950 5735);
WIRE 16 -1 (-3375 4150)(-2200 4150);
FORCEPROP 0 LAST CDS_PHYS_NET_NAME IRQ_LVC3_WAKE_N
J 0
(-3350 4192);
PAINT MONO (-3350 4192);
DISPLAY INVISIBLE (-3350 4192);
FORCEPROP 0 LAST SIG_NAME IRQ_OCP_SFF_WAKE_BUF_N
J 0
(-2960 4160);
DISPLAY 0.702128 (-2960 4160);
PAINT WHITE (-2960 4160);
WIRE 16 -1 (-3475 3375)(-4525 3375);
FORCEPROP 0 LAST CDS_PHYS_NET_NAME CLK_50M_NCSI_OCP_SFF
J 0
(-4160 3409);
PAINT MONO (-4160 3409);
DISPLAY INVISIBLE (-4160 3409);
FORCEPROP 2 LAST SIG_NAME CLK_50M_NCSI_OCP_SFF
J 0
(-4285 3385);
DISPLAY 0.510638 (-4285 3385);
PAINT WHITE (-4285 3385);
WIRE 16 -1 (-2150 3225)(-2875 3225);
FORCEPROP 2 LAST SIG_NAME FB_BMC_ISOLATE
J 0
(-2685 3235);
DISPLAY 0.553191 (-2685 3235);
PAINT WHITE (-2685 3235);
WIRE 16 -1 (-2875 3375)(-2725 3375);
WIRE 16 -1 (-2725 3725)(-2725 3375);
WIRE 16 -1 (-2725 3725)(-2525 3725);
WIRE 16 -1 (-2725 3775)(-2725 3725);
WIRE 16 -1 (-2525 3725)(-2525 3650);
WIRE 16 -1 (-6675 2275)(-6550 2275);
WIRE 16 -1 (-6550 2200)(-6550 2275);
WIRE 16 -1 (-6675 2625)(-6475 2625);
WIRE 16 -1 (-6475 2625)(-6475 3050);
WIRE 16 -1 (-6250 3050)(-6475 3050);
WIRE 16 -1 (-6475 3050)(-6475 3125);
WIRE 16 -1 (-6250 2950)(-6250 3050);
WIRE 16 -1 (-8175 4500)(-8175 5000);
FORCEPROP 0 LAST VOLTAGE 3.3
J 0
(-8075 4500);
PAINT MONO (-8075 4500);
DISPLAY INVISIBLE (-8075 4500);
FORCEPROP 0 LAST CDS_PHYS_NET_NAME P3V3_AUX
J 0
(-8075 4547);
PAINT MONO (-8075 4547);
DISPLAY INVISIBLE (-8075 4547);
FORCEPROP 0 LAST $PHYS_NET_NAME P3V3_AUX
J 0
(-8075 4594);
PAINT MONO (-8075 4594);
DISPLAY INVISIBLE (-8075 4594);
WIRE 16 -1 (-8175 5000)(-7900 5000);
WIRE 16 -1 (-7900 4900)(-7900 5000);
WIRE 16 -1 (-7900 5000)(-7900 5100);
WIRE 16 -1 (-4675 4350)(-4525 4350);
WIRE 16 -1 (-4525 4700)(-4525 4350);
WIRE 16 -1 (-4525 4700)(-4325 4700);
WIRE 16 -1 (-4525 4750)(-4525 4700);
WIRE 16 -1 (-4325 4700)(-4325 4625);
WIRE 16 -1 (-9600 2525)(-9775 2525);
WIRE 16 -1 (-9775 2525)(-9775 2975);
WIRE 16 -1 (-9775 2975)(-9875 2975);
WIRE 16 -1 (-9775 2975)(-9775 3075);
WIRE 16 -1 (-9875 2850)(-9875 2975);
WIRE 16 -1 (-10225 2975)(-9875 2975);
WIRE 16 -1 (-10225 2825)(-10225 2975);
WIRE 16 -1 (-8950 2375)(-8825 2375);
WIRE 16 -1 (-8825 2300)(-8825 2375);
WIRE 16 -1 (-4400 2475)(-5450 2475);
FORCEPROP 0 LAST CDS_PHYS_NET_NAME CLK_50M_NCSI_OCP_SFF
J 0
(-5085 2509);
PAINT MONO (-5085 2509);
DISPLAY INVISIBLE (-5085 2509);
FORCEPROP 2 LAST SIG_NAME CLK_50M_NCSI_OCP_SFF
J 0
(-4960 2485);
DISPLAY 0.510638 (-4960 2485);
PAINT WHITE (-4960 2485);
WIRE 16 -1 (-5650 2425)(-6675 2425);
FORCEPROP 0 LAST CDS_PHYS_NET_NAME CLK_50M_NCSI_OCP_2
J 0
(-6310 2459);
PAINT MONO (-6310 2459);
DISPLAY INVISIBLE (-6310 2459);
FORCEPROP 2 LAST SIG_NAME CLK_50M_NCSI_OCP_2
J 0
(-6385 2435);
DISPLAY 0.510638 (-6385 2435);
PAINT WHITE (-6385 2435);
FORCEPROP 2 LASTPROP $XRERR UNIQUE?
J 0
(-6625 2435);
DISPLAY 0.638298 (-6625 2435);
PAINT MONO (-6625 2435);
DISPLAY INVISIBLE (-6625 2435);
WIRE 16 -1 (-5650 2375)(-6675 2375);
FORCEPROP 0 LAST CDS_PHYS_NET_NAME TP_CLK_50M_PCH_LOM
J 0
(-6310 2409);
PAINT MONO (-6310 2409);
DISPLAY INVISIBLE (-6310 2409);
FORCEPROP 2 LAST SIG_NAME TP_CLK_50M_Y3
J 0
(-6385 2385);
DISPLAY 0.510638 (-6385 2385);
PAINT WHITE (-6385 2385);
FORCEPROP 2 LASTPROP $XRERR UNIQUE?
J 0
(-5620 2375);
DISPLAY 0.638298 (-5620 2375);
PAINT MONO (-5620 2375);
DISPLAY INVISIBLE (-5620 2375);
WIRE 16 -1 (-5650 2475)(-6675 2475);
FORCEPROP 0 LAST CDS_PHYS_NET_NAME CLK_50M_NCSI_OCP_1
J 0
(-6310 2509);
PAINT MONO (-6310 2509);
DISPLAY INVISIBLE (-6310 2509);
FORCEPROP 2 LAST SIG_NAME CLK_50M_NCSI_OCP_1
J 0
(-6385 2485);
DISPLAY 0.510638 (-6385 2485);
PAINT WHITE (-6385 2485);
FORCEPROP 2 LASTPROP $XRERR UNIQUE?
J 0
(-6625 2485);
DISPLAY 0.638298 (-6625 2485);
PAINT MONO (-6625 2485);
DISPLAY INVISIBLE (-6625 2485);
WIRE 16 -1 (-4125 5725)(-5225 5725);
FORCEPROP 0 LAST CDS_PHYS_NET_NAME OCP_SFF_PWRBRK_N
J 0
(-4685 5767);
PAINT MONO (-4685 5767);
DISPLAY INVISIBLE (-4685 5767);
FORCEPROP 2 LAST SIG_NAME OCP_SFF_PWRBRK_N
J 0
(-4735 5735);
DISPLAY 0.680851 (-4735 5735);
PAINT WHITE (-4735 5735);
WIRE 16 -1 (-5225 4250)(-6625 4250);
FORCEPROP 0 LAST CDS_PHYS_NET_NAME OCP_SFF_WAKE_BUFF_R_N
J 0
(-5960 4292);
PAINT MONO (-5960 4292);
DISPLAY INVISIBLE (-5960 4292);
FORCEPROP 2 LAST SIG_NAME OCP_SFF_WAKE_BUFF_R_N
J 0
(-6135 4260);
DISPLAY 0.680851 (-6135 4260);
PAINT WHITE (-6135 4260);
FORCEPROP 2 LASTPROP $XRERR UNIQUE?
J 0
(-6375 4260);
DISPLAY 0.638298 (-6375 4260);
PAINT MONO (-6375 4260);
DISPLAY INVISIBLE (-6375 4260);
WIRE 16 -1 (-7925 4250)(-7050 4250);
FORCEPROP 0 LAST CDS_PHYS_NET_NAME OCP_SFF_WAKE_BUFF_N
J 0
(-7560 4292);
PAINT MONO (-7560 4292);
DISPLAY INVISIBLE (-7560 4292);
FORCEPROP 2 LAST SIG_NAME OCP_SFF_WAKE_BUFF_N
J 0
(-7785 4260);
DISPLAY 0.680851 (-7785 4260);
PAINT WHITE (-7785 4260);
FORCEPROP 2 LASTPROP $XRERR UNIQUE?
J 0
(-8025 4260);
DISPLAY 0.638298 (-8025 4260);
PAINT MONO (-8025 4260);
DISPLAY INVISIBLE (-8025 4260);
WIRE 16 -1 (-6825 4250)(-7050 4250);
WIRE 16 -1 (-7050 4600)(-7050 4250);
WIRE 16 -1 (-5650 2525)(-6675 2525);
FORCEPROP 0 LAST CDS_PHYS_NET_NAME CLK_50M_BMC_MAC_R
J 0
(-6310 2559);
PAINT MONO (-6310 2559);
DISPLAY INVISIBLE (-6310 2559);
FORCEPROP 2 LAST SIG_NAME CLK_50M_BMC_MAC_R
J 0
(-6385 2535);
DISPLAY 0.510638 (-6385 2535);
PAINT WHITE (-6385 2535);
FORCEPROP 2 LASTPROP $XRERR UNIQUE?
J 0
(-6625 2535);
DISPLAY 0.638298 (-6625 2535);
PAINT MONO (-6625 2535);
DISPLAY INVISIBLE (-6625 2535);
WIRE 16 -1 (-10225 2625)(-10225 2375);
WIRE 16 -1 (-9600 2375)(-10225 2375);
FORCEPROP 2 LAST SIG_NAME CLK_50M_EN
J 0
(-10010 2385);
DISPLAY 0.638298 (-10010 2385);
PAINT WHITE (-10010 2385);
FORCEPROP 2 LASTPROP $XRERR UNIQUE?
J 0
(-10250 2385);
DISPLAY 0.638298 (-10250 2385);
PAINT MONO (-10250 2385);
DISPLAY INVISIBLE (-10250 2385);
WIRE 16 -1 (-10225 2375)(-10225 2150);
WIRE 16 -1 (-10225 2150)(-8000 2150);
WIRE 16 -1 (-8000 2150)(-8000 2375);
WIRE 16 -1 (-8000 2375)(-7275 2375);
WIRE 16 -1 (-7275 2525)(-8050 2525);
FORCEPROP 2 LAST SIG_NAME CLK_50M_RMII_R
J 0
(-7810 2535);
DISPLAY 0.553191 (-7810 2535);
PAINT WHITE (-7810 2535);
FORCEPROP 2 LASTPROP $XRERR UNIQUE?
J 0
(-8050 2535);
DISPLAY 0.638298 (-8050 2535);
PAINT MONO (-8050 2535);
DISPLAY INVISIBLE (-8050 2535);
WIRE 16 -1 (-7525 5825)(-8650 5825);
FORCEPROP 0 LAST CDS_PHYS_NET_NAME FM_SYS_THROTTLE_N
J 0
(-8625 5867);
PAINT MONO (-8625 5867);
DISPLAY INVISIBLE (-8625 5867);
FORCEPROP 0 LAST SIG_NAME FM_SYS_THROTTLE_N
J 0
(-8425 5835);
DISPLAY 0.702128 (-8425 5835);
PAINT WHITE (-8425 5835);
WIRE 16 -1 (-7525 5925)(-8650 5925);
FORCEPROP 0 LAST CDS_PHYS_NET_NAME NC_U104_NC1
J 0
(-8625 5967);
PAINT MONO (-8625 5967);
DISPLAY INVISIBLE (-8625 5967);
FORCEPROP 0 LAST SIG_NAME NC_U104_NC1
J 0
(-8435 5935);
DISPLAY 0.702128 (-8435 5935);
PAINT WHITE (-8435 5935);
FORCEPROP 2 LASTPROP $XRERR UNIQUE?
J 0
(-8890 5925);
DISPLAY 0.638298 (-8890 5925);
PAINT MONO (-8890 5925);
DISPLAY INVISIBLE (-8890 5925);
WIRE 16 -1 (-9675 4725)(-9675 4850);
WIRE 16 -1 (-9675 4850)(-9400 4850);
WIRE 16 -1 (-9400 4850)(-9400 4925);
WIRE 16 -1 (-9400 4725)(-9400 4850);
WIRE 16 -1 (-9675 4525)(-9675 4300);
WIRE 16 -1 (-9675 4300)(-8425 4300);
FORCEPROP 2 LAST SIG_NAME IRQ_LVC3_OCP_SFF_WAKE_N
J 0
(-9285 4310);
DISPLAY 0.680851 (-9285 4310);
PAINT WHITE (-9285 4310);
WIRE 16 -1 (-10150 4300)(-9675 4300);
FORCEPROP 0 LAST CDS_PHYS_NET_NAME IRQ_LVC3_OCP_SFF_WAKE_N
J 0
(-9685 4342);
PAINT MONO (-9685 4342);
DISPLAY INVISIBLE (-9685 4342);
WIRE 16 -1 (-8950 2525)(-8250 2525);
FORCEPROP 2 LAST SIG_NAME CLK_50M_RMII
J 0
(-8835 2535);
DISPLAY 0.553191 (-8835 2535);
PAINT WHITE (-8835 2535);
FORCEPROP 2 LASTPROP $XRERR UNIQUE?
J 0
(-9075 2535);
DISPLAY 0.638298 (-9075 2535);
PAINT MONO (-9075 2535);
DISPLAY INVISIBLE (-9075 2535);
DOT 1 (-7250 6975);
DOT 1 (-7250 7025);
DOT 1 (-8275 7525);
DOT 1 (-10225 2375);
DOT 1 (-9875 2975);
DOT 1 (-9775 2975);
DOT 1 (-9675 4300);
DOT 1 (-9400 4850);
DOT 1 (-6475 3050);
DOT 1 (-7050 4250);
DOT 1 (-7900 5000);
DOT 1 (-6775 6375);
DOT 1 (-5875 5725);
DOT 1 (-4525 4700);
DOT 1 (-3775 4150);
DOT 1 (-2725 3725);
CIRCLE (-5625 6225)(-5465 6225);
PAINT YELLOW (-5625 6225);
DOT 1 (-7250 6925);
FORCENOTE
POP
(-5650 6200) 0;
DISPLAY LEFT (-5650 6200);
DISPLAY 1.021277 (-5650 6200);
QUIT
